FILE_TYPE = MACRO_DRAWING;
SET COLOR_WIRE YELLOW;
SET COLOR_PROP ORANGE;
SET COLOR_DOT WHITE;
SET COLOR_ARC YELLOW;
SET COLOR_BODY GREEN;
SET COLOR_NOTE PURPLE;
SET PROP_DISPLAY VALUE;
SET PAGE_NUMBER P29;
FORCEADD SOCKET4677_AZIF0045P001C01CS..18
(1400 325);
FORCEPROP 1 LAST PART_NUMBER DGA^7000023
J 0
(350 1375);
DISPLAY 0.723404 (350 1375);
PAINT GREEN (350 1375);
DISPLAY INVISIBLE (350 1375);
FORCEPROP 2 LAST VALUE SOCKET4677_AZIF0045-P001C01CS
J 0
(350 1500);
DISPLAY 1.021277 (350 1500);
FORCEPROP 1 LAST MATERIAL IO
J 0
(350 1300);
DISPLAY 0.723404 (350 1300);
PAINT GREEN (350 1300);
FORCEPROP 2 LAST PART_TYPE SMLF
J 0
(350 1550);
DISPLAY 1.021277 (350 1550);
FORCEPROP 1 LAST $LOCATION U2
J 0
(350 1450);
DISPLAY 0.723404 (350 1450);
PAINT GREEN (350 1450);
FORCEPROP 0 LASTPIN (200 -475) $PN CP10
J 2
(190 -465);
DISPLAY 0.680851 (190 -465);
PAINT MONO (190 -465);
FORCEPROP 0 LASTPIN (200 -425) $PN CL11
J 2
(190 -415);
DISPLAY 0.680851 (190 -415);
PAINT MONO (190 -415);
FORCEPROP 0 LASTPIN (200 -375) $PN CK10
J 2
(190 -365);
DISPLAY 0.680851 (190 -365);
PAINT MONO (190 -365);
FORCEPROP 0 LASTPIN (200 -325) $PN CG11
J 2
(190 -315);
DISPLAY 0.680851 (190 -315);
PAINT MONO (190 -315);
FORCEPROP 0 LASTPIN (200 -275) $PN CF10
J 2
(190 -265);
DISPLAY 0.680851 (190 -265);
PAINT MONO (190 -265);
FORCEPROP 0 LASTPIN (200 -225) $PN CC11
J 2
(190 -215);
DISPLAY 0.680851 (190 -215);
PAINT MONO (190 -215);
FORCEPROP 0 LASTPIN (200 -175) $PN CB10
J 2
(190 -165);
DISPLAY 0.680851 (190 -165);
PAINT MONO (190 -165);
FORCEPROP 0 LASTPIN (200 -125) $PN BW11
J 2
(190 -115);
DISPLAY 0.680851 (190 -115);
PAINT MONO (190 -115);
FORCEPROP 0 LASTPIN (200 -75) $PN BV10
J 2
(190 -65);
DISPLAY 0.680851 (190 -65);
PAINT MONO (190 -65);
FORCEPROP 0 LASTPIN (200 -25) $PN BR11
J 2
(190 -15);
DISPLAY 0.680851 (190 -15);
PAINT MONO (190 -15);
FORCEPROP 0 LASTPIN (200 25) $PN BP10
J 2
(190 35);
DISPLAY 0.680851 (190 35);
PAINT MONO (190 35);
FORCEPROP 0 LASTPIN (200 75) $PN BL11
J 2
(190 85);
DISPLAY 0.680851 (190 85);
PAINT MONO (190 85);
FORCEPROP 0 LASTPIN (200 125) $PN BK10
J 2
(190 135);
DISPLAY 0.680851 (190 135);
PAINT MONO (190 135);
FORCEPROP 0 LASTPIN (200 175) $PN BG11
J 2
(190 185);
DISPLAY 0.680851 (190 185);
PAINT MONO (190 185);
FORCEPROP 0 LASTPIN (200 225) $PN BF10
J 2
(190 235);
DISPLAY 0.680851 (190 235);
PAINT MONO (190 235);
FORCEPROP 0 LASTPIN (200 275) $PN BC11
J 2
(190 285);
DISPLAY 0.680851 (190 285);
PAINT MONO (190 285);
FORCEPROP 0 LASTPIN (200 375) $PN CN9
J 2
(190 385);
DISPLAY 0.680851 (190 385);
PAINT MONO (190 385);
FORCEPROP 0 LASTPIN (200 425) $PN CM10
J 2
(190 435);
DISPLAY 0.680851 (190 435);
PAINT MONO (190 435);
FORCEPROP 0 LASTPIN (200 475) $PN CJ9
J 2
(190 485);
DISPLAY 0.680851 (190 485);
PAINT MONO (190 485);
FORCEPROP 0 LASTPIN (200 525) $PN CH10
J 2
(190 535);
DISPLAY 0.680851 (190 535);
PAINT MONO (190 535);
FORCEPROP 0 LASTPIN (200 575) $PN CE9
J 2
(190 585);
DISPLAY 0.680851 (190 585);
PAINT MONO (190 585);
FORCEPROP 0 LASTPIN (200 625) $PN CD10
J 2
(190 635);
DISPLAY 0.680851 (190 635);
PAINT MONO (190 635);
FORCEPROP 0 LASTPIN (200 675) $PN CA9
J 2
(190 685);
DISPLAY 0.680851 (190 685);
PAINT MONO (190 685);
FORCEPROP 0 LASTPIN (200 725) $PN BY10
J 2
(190 735);
DISPLAY 0.680851 (190 735);
PAINT MONO (190 735);
FORCEPROP 0 LASTPIN (200 775) $PN BU9
J 2
(190 785);
DISPLAY 0.680851 (190 785);
PAINT MONO (190 785);
FORCEPROP 0 LASTPIN (200 825) $PN BT10
J 2
(190 835);
DISPLAY 0.680851 (190 835);
PAINT MONO (190 835);
FORCEPROP 0 LASTPIN (200 875) $PN BN9
J 2
(190 885);
DISPLAY 0.680851 (190 885);
PAINT MONO (190 885);
FORCEPROP 0 LASTPIN (200 925) $PN BM10
J 2
(190 935);
DISPLAY 0.680851 (190 935);
PAINT MONO (190 935);
FORCEPROP 0 LASTPIN (200 975) $PN BJ9
J 2
(190 985);
DISPLAY 0.680851 (190 985);
PAINT MONO (190 985);
FORCEPROP 0 LASTPIN (200 1025) $PN BH10
J 2
(190 1035);
DISPLAY 0.680851 (190 1035);
PAINT MONO (190 1035);
FORCEPROP 0 LASTPIN (200 1075) $PN BE9
J 2
(190 1085);
DISPLAY 0.680851 (190 1085);
PAINT MONO (190 1085);
FORCEPROP 0 LASTPIN (200 1125) $PN BD10
J 2
(190 1135);
DISPLAY 0.680851 (190 1135);
PAINT MONO (190 1135);
FORCEPROP 0 LASTPIN (2600 -475) $PN CP14
J 0
(2610 -465);
DISPLAY 0.680851 (2610 -465);
PAINT MONO (2610 -465);
FORCEPROP 0 LASTPIN (2600 -425) $PN CN13
J 0
(2610 -415);
DISPLAY 0.680851 (2610 -415);
PAINT MONO (2610 -415);
FORCEPROP 0 LASTPIN (2600 -375) $PN CK14
J 0
(2610 -365);
DISPLAY 0.680851 (2610 -365);
PAINT MONO (2610 -365);
FORCEPROP 0 LASTPIN (2600 -325) $PN CJ13
J 0
(2610 -315);
DISPLAY 0.680851 (2610 -315);
PAINT MONO (2610 -315);
FORCEPROP 0 LASTPIN (2600 -275) $PN CF14
J 0
(2610 -265);
DISPLAY 0.680851 (2610 -265);
PAINT MONO (2610 -265);
FORCEPROP 0 LASTPIN (2600 -225) $PN CE13
J 0
(2610 -215);
DISPLAY 0.680851 (2610 -215);
PAINT MONO (2610 -215);
FORCEPROP 0 LASTPIN (2600 -175) $PN CB14
J 0
(2610 -165);
DISPLAY 0.680851 (2610 -165);
PAINT MONO (2610 -165);
FORCEPROP 0 LASTPIN (2600 -125) $PN CA13
J 0
(2610 -115);
DISPLAY 0.680851 (2610 -115);
PAINT MONO (2610 -115);
FORCEPROP 0 LASTPIN (2600 -75) $PN BV14
J 0
(2610 -65);
DISPLAY 0.680851 (2610 -65);
PAINT MONO (2610 -65);
FORCEPROP 0 LASTPIN (2600 -25) $PN BU13
J 0
(2610 -15);
DISPLAY 0.680851 (2610 -15);
PAINT MONO (2610 -15);
FORCEPROP 0 LASTPIN (2600 25) $PN BP14
J 0
(2610 35);
DISPLAY 0.680851 (2610 35);
PAINT MONO (2610 35);
FORCEPROP 0 LASTPIN (2600 75) $PN BN13
J 0
(2610 85);
DISPLAY 0.680851 (2610 85);
PAINT MONO (2610 85);
FORCEPROP 0 LASTPIN (2600 125) $PN BK14
J 0
(2610 135);
DISPLAY 0.680851 (2610 135);
PAINT MONO (2610 135);
FORCEPROP 0 LASTPIN (2600 175) $PN BJ13
J 0
(2610 185);
DISPLAY 0.680851 (2610 185);
PAINT MONO (2610 185);
FORCEPROP 0 LASTPIN (2600 225) $PN BF14
J 0
(2610 235);
DISPLAY 0.680851 (2610 235);
PAINT MONO (2610 235);
FORCEPROP 0 LASTPIN (2600 275) $PN BE13
J 0
(2610 285);
DISPLAY 0.680851 (2610 285);
PAINT MONO (2610 285);
FORCEPROP 0 LASTPIN (2600 375) $PN CR15
J 0
(2610 385);
DISPLAY 0.680851 (2610 385);
PAINT MONO (2610 385);
FORCEPROP 0 LASTPIN (2600 425) $PN CM14
J 0
(2610 435);
DISPLAY 0.680851 (2610 435);
PAINT MONO (2610 435);
FORCEPROP 0 LASTPIN (2600 475) $PN CL15
J 0
(2610 485);
DISPLAY 0.680851 (2610 485);
PAINT MONO (2610 485);
FORCEPROP 0 LASTPIN (2600 525) $PN CH14
J 0
(2610 535);
DISPLAY 0.680851 (2610 535);
PAINT MONO (2610 535);
FORCEPROP 0 LASTPIN (2600 575) $PN CG15
J 0
(2610 585);
DISPLAY 0.680851 (2610 585);
PAINT MONO (2610 585);
FORCEPROP 0 LASTPIN (2600 625) $PN CD14
J 0
(2610 635);
DISPLAY 0.680851 (2610 635);
PAINT MONO (2610 635);
FORCEPROP 0 LASTPIN (2600 675) $PN CC15
J 0
(2610 685);
DISPLAY 0.680851 (2610 685);
PAINT MONO (2610 685);
FORCEPROP 0 LASTPIN (2600 725) $PN BY14
J 0
(2610 735);
DISPLAY 0.680851 (2610 735);
PAINT MONO (2610 735);
FORCEPROP 0 LASTPIN (2600 775) $PN BW15
J 0
(2610 785);
DISPLAY 0.680851 (2610 785);
PAINT MONO (2610 785);
FORCEPROP 0 LASTPIN (2600 825) $PN BT14
J 0
(2610 835);
DISPLAY 0.680851 (2610 835);
PAINT MONO (2610 835);
FORCEPROP 0 LASTPIN (2600 875) $PN BR15
J 0
(2610 885);
DISPLAY 0.680851 (2610 885);
PAINT MONO (2610 885);
FORCEPROP 0 LASTPIN (2600 925) $PN BM14
J 0
(2610 935);
DISPLAY 0.680851 (2610 935);
PAINT MONO (2610 935);
FORCEPROP 0 LASTPIN (2600 975) $PN BL15
J 0
(2610 985);
DISPLAY 0.680851 (2610 985);
PAINT MONO (2610 985);
FORCEPROP 0 LASTPIN (2600 1025) $PN BH14
J 0
(2610 1035);
DISPLAY 0.680851 (2610 1035);
PAINT MONO (2610 1035);
FORCEPROP 0 LASTPIN (2600 1075) $PN BG15
J 0
(2610 1085);
DISPLAY 0.680851 (2610 1085);
PAINT MONO (2610 1085);
FORCEPROP 0 LASTPIN (2600 1125) $PN BD14
J 0
(2610 1135);
DISPLAY 0.680851 (2610 1135);
PAINT MONO (2610 1135);
FORCEPROP 1 LAST CDS_LMAN_SYM_OUTLINE -1050,950,1050,-950
J 0
(1400 325);
DISPLAY 0.468085 (1400 325);
PAINT GREEN (1400 325);
DISPLAY INVISIBLE (1400 325);
FORCEPROP 1 LAST NEEDS_NO_SIZE TRUE
J 0
(1400 325);
DISPLAY 0.723404 (1400 325);
PAINT GREEN (1400 325);
DISPLAY INVISIBLE (1400 325);
FORCEPROP 2 LAST CDS_LIB pure_quanta
J 0
(1400 325);
DISPLAY INVISIBLE (1400 325);
FORCEPROP 2 LAST CDS_LOCATION U2
J 0
(350 1600);
DISPLAY 1.021277 (350 1600);
DISPLAY INVISIBLE (350 1600);
FORCEPROP 0 LAST $SEC 18
J 0
(350 1600);
DISPLAY 0.680851 (350 1600);
PAINT MONO (350 1600);
DISPLAY INVISIBLE (350 1600);
FORCEPROP 2 LAST CDS_SEC 18
J 0
(350 1600);
DISPLAY 1.021277 (350 1600);
DISPLAY INVISIBLE (350 1600);
FORCEPROP 1 LAST PATH I176
J 0
(1400 325);
DISPLAY 0.723404 (1400 325);
PAINT GREEN (1400 325);
DISPLAY INVISIBLE (1400 325);
FORCEADD SOCKET4677_AZIF0045P001C01CS..17
(1400 3075);
FORCEPROP 1 LAST PART_NUMBER DGA^7000023
J 0
(350 4125);
DISPLAY 0.723404 (350 4125);
PAINT GREEN (350 4125);
DISPLAY INVISIBLE (350 4125);
FORCEPROP 2 LAST VALUE SOCKET4677_AZIF0045-P001C01CS
J 0
(350 4250);
DISPLAY 1.021277 (350 4250);
FORCEPROP 1 LAST MATERIAL IO
J 0
(350 4050);
DISPLAY 0.723404 (350 4050);
PAINT GREEN (350 4050);
FORCEPROP 2 LAST PART_TYPE SMLF
J 0
(350 4300);
DISPLAY 1.021277 (350 4300);
FORCEPROP 1 LAST $LOCATION U2
J 0
(350 4200);
DISPLAY 0.723404 (350 4200);
PAINT GREEN (350 4200);
FORCEPROP 0 LASTPIN (200 2275) $PN K10
J 2
(190 2285);
DISPLAY 0.680851 (190 2285);
PAINT MONO (190 2285);
FORCEPROP 0 LASTPIN (200 2325) $PN M10
J 2
(190 2335);
DISPLAY 0.680851 (190 2335);
PAINT MONO (190 2335);
FORCEPROP 0 LASTPIN (200 2375) $PN P10
J 2
(190 2385);
DISPLAY 0.680851 (190 2385);
PAINT MONO (190 2385);
FORCEPROP 0 LASTPIN (200 2425) $PN T10
J 2
(190 2435);
DISPLAY 0.680851 (190 2435);
PAINT MONO (190 2435);
FORCEPROP 0 LASTPIN (200 2475) $PN V10
J 2
(190 2485);
DISPLAY 0.680851 (190 2485);
PAINT MONO (190 2485);
FORCEPROP 0 LASTPIN (200 2525) $PN AA9
J 2
(190 2535);
DISPLAY 0.680851 (190 2535);
PAINT MONO (190 2535);
FORCEPROP 0 LASTPIN (200 2575) $PN AB10
J 2
(190 2585);
DISPLAY 0.680851 (190 2585);
PAINT MONO (190 2585);
FORCEPROP 0 LASTPIN (200 2625) $PN AE9
J 2
(190 2635);
DISPLAY 0.680851 (190 2635);
PAINT MONO (190 2635);
FORCEPROP 0 LASTPIN (200 2675) $PN AF10
J 2
(190 2685);
DISPLAY 0.680851 (190 2685);
PAINT MONO (190 2685);
FORCEPROP 0 LASTPIN (200 2725) $PN AJ9
J 2
(190 2735);
DISPLAY 0.680851 (190 2735);
PAINT MONO (190 2735);
FORCEPROP 0 LASTPIN (200 2775) $PN AK10
J 2
(190 2785);
DISPLAY 0.680851 (190 2785);
PAINT MONO (190 2785);
FORCEPROP 0 LASTPIN (200 2825) $PN AM10
J 2
(190 2835);
DISPLAY 0.680851 (190 2835);
PAINT MONO (190 2835);
FORCEPROP 0 LASTPIN (200 2875) $PN AP10
J 2
(190 2885);
DISPLAY 0.680851 (190 2885);
PAINT MONO (190 2885);
FORCEPROP 0 LASTPIN (200 2925) $PN AU9
J 2
(190 2935);
DISPLAY 0.680851 (190 2935);
PAINT MONO (190 2935);
FORCEPROP 0 LASTPIN (200 2975) $PN AV10
J 2
(190 2985);
DISPLAY 0.680851 (190 2985);
PAINT MONO (190 2985);
FORCEPROP 0 LASTPIN (200 3025) $PN BA9
J 2
(190 3035);
DISPLAY 0.680851 (190 3035);
PAINT MONO (190 3035);
FORCEPROP 0 LASTPIN (200 3125) $PN L11
J 2
(190 3135);
DISPLAY 0.680851 (190 3135);
PAINT MONO (190 3135);
FORCEPROP 0 LASTPIN (200 3175) $PN N9
J 2
(190 3185);
DISPLAY 0.680851 (190 3185);
PAINT MONO (190 3185);
FORCEPROP 0 LASTPIN (200 3225) $PN R11
J 2
(190 3235);
DISPLAY 0.680851 (190 3235);
PAINT MONO (190 3235);
FORCEPROP 0 LASTPIN (200 3275) $PN U9
J 2
(190 3285);
DISPLAY 0.680851 (190 3285);
PAINT MONO (190 3285);
FORCEPROP 0 LASTPIN (200 3325) $PN W11
J 2
(190 3335);
DISPLAY 0.680851 (190 3335);
PAINT MONO (190 3335);
FORCEPROP 0 LASTPIN (200 3375) $PN Y10
J 2
(190 3385);
DISPLAY 0.680851 (190 3385);
PAINT MONO (190 3385);
FORCEPROP 0 LASTPIN (200 3425) $PN AC11
J 2
(190 3435);
DISPLAY 0.680851 (190 3435);
PAINT MONO (190 3435);
FORCEPROP 0 LASTPIN (200 3475) $PN AD10
J 2
(190 3485);
DISPLAY 0.680851 (190 3485);
PAINT MONO (190 3485);
FORCEPROP 0 LASTPIN (200 3525) $PN AG11
J 2
(190 3535);
DISPLAY 0.680851 (190 3535);
PAINT MONO (190 3535);
FORCEPROP 0 LASTPIN (200 3575) $PN AH10
J 2
(190 3585);
DISPLAY 0.680851 (190 3585);
PAINT MONO (190 3585);
FORCEPROP 0 LASTPIN (200 3625) $PN AL11
J 2
(190 3635);
DISPLAY 0.680851 (190 3635);
PAINT MONO (190 3635);
FORCEPROP 0 LASTPIN (200 3675) $PN AN9
J 2
(190 3685);
DISPLAY 0.680851 (190 3685);
PAINT MONO (190 3685);
FORCEPROP 0 LASTPIN (200 3725) $PN AR11
J 2
(190 3735);
DISPLAY 0.680851 (190 3735);
PAINT MONO (190 3735);
FORCEPROP 0 LASTPIN (200 3775) $PN AT10
J 2
(190 3785);
DISPLAY 0.680851 (190 3785);
PAINT MONO (190 3785);
FORCEPROP 0 LASTPIN (200 3825) $PN AW11
J 2
(190 3835);
DISPLAY 0.680851 (190 3835);
PAINT MONO (190 3835);
FORCEPROP 0 LASTPIN (200 3875) $PN AY10
J 2
(190 3885);
DISPLAY 0.680851 (190 3885);
PAINT MONO (190 3885);
FORCEPROP 0 LASTPIN (2600 2275) $PN N13
J 0
(2610 2285);
DISPLAY 0.680851 (2610 2285);
PAINT MONO (2610 2285);
FORCEPROP 0 LASTPIN (2600 2325) $PN P14
J 0
(2610 2335);
DISPLAY 0.680851 (2610 2335);
PAINT MONO (2610 2335);
FORCEPROP 0 LASTPIN (2600 2375) $PN U13
J 0
(2610 2385);
DISPLAY 0.680851 (2610 2385);
PAINT MONO (2610 2385);
FORCEPROP 0 LASTPIN (2600 2425) $PN V14
J 0
(2610 2435);
DISPLAY 0.680851 (2610 2435);
PAINT MONO (2610 2435);
FORCEPROP 0 LASTPIN (2600 2475) $PN AA13
J 0
(2610 2485);
DISPLAY 0.680851 (2610 2485);
PAINT MONO (2610 2485);
FORCEPROP 0 LASTPIN (2600 2525) $PN AB14
J 0
(2610 2535);
DISPLAY 0.680851 (2610 2535);
PAINT MONO (2610 2535);
FORCEPROP 0 LASTPIN (2600 2575) $PN AE13
J 0
(2610 2585);
DISPLAY 0.680851 (2610 2585);
PAINT MONO (2610 2585);
FORCEPROP 0 LASTPIN (2600 2625) $PN AF14
J 0
(2610 2635);
DISPLAY 0.680851 (2610 2635);
PAINT MONO (2610 2635);
FORCEPROP 0 LASTPIN (2600 2675) $PN AJ13
J 0
(2610 2685);
DISPLAY 0.680851 (2610 2685);
PAINT MONO (2610 2685);
FORCEPROP 0 LASTPIN (2600 2725) $PN AK14
J 0
(2610 2735);
DISPLAY 0.680851 (2610 2735);
PAINT MONO (2610 2735);
FORCEPROP 0 LASTPIN (2600 2775) $PN AN13
J 0
(2610 2785);
DISPLAY 0.680851 (2610 2785);
PAINT MONO (2610 2785);
FORCEPROP 0 LASTPIN (2600 2825) $PN AP14
J 0
(2610 2835);
DISPLAY 0.680851 (2610 2835);
PAINT MONO (2610 2835);
FORCEPROP 0 LASTPIN (2600 2875) $PN AU13
J 0
(2610 2885);
DISPLAY 0.680851 (2610 2885);
PAINT MONO (2610 2885);
FORCEPROP 0 LASTPIN (2600 2925) $PN AV14
J 0
(2610 2935);
DISPLAY 0.680851 (2610 2935);
PAINT MONO (2610 2935);
FORCEPROP 0 LASTPIN (2600 2975) $PN BA13
J 0
(2610 2985);
DISPLAY 0.680851 (2610 2985);
PAINT MONO (2610 2985);
FORCEPROP 0 LASTPIN (2600 3025) $PN BB14
J 0
(2610 3035);
DISPLAY 0.680851 (2610 3035);
PAINT MONO (2610 3035);
FORCEPROP 0 LASTPIN (2600 3125) $PN M14
J 0
(2610 3135);
DISPLAY 0.680851 (2610 3135);
PAINT MONO (2610 3135);
FORCEPROP 0 LASTPIN (2600 3175) $PN R15
J 0
(2610 3185);
DISPLAY 0.680851 (2610 3185);
PAINT MONO (2610 3185);
FORCEPROP 0 LASTPIN (2600 3225) $PN T14
J 0
(2610 3235);
DISPLAY 0.680851 (2610 3235);
PAINT MONO (2610 3235);
FORCEPROP 0 LASTPIN (2600 3275) $PN W15
J 0
(2610 3285);
DISPLAY 0.680851 (2610 3285);
PAINT MONO (2610 3285);
FORCEPROP 0 LASTPIN (2600 3325) $PN Y14
J 0
(2610 3335);
DISPLAY 0.680851 (2610 3335);
PAINT MONO (2610 3335);
FORCEPROP 0 LASTPIN (2600 3375) $PN AC15
J 0
(2610 3385);
DISPLAY 0.680851 (2610 3385);
PAINT MONO (2610 3385);
FORCEPROP 0 LASTPIN (2600 3425) $PN AD14
J 0
(2610 3435);
DISPLAY 0.680851 (2610 3435);
PAINT MONO (2610 3435);
FORCEPROP 0 LASTPIN (2600 3475) $PN AG15
J 0
(2610 3485);
DISPLAY 0.680851 (2610 3485);
PAINT MONO (2610 3485);
FORCEPROP 0 LASTPIN (2600 3525) $PN AH14
J 0
(2610 3535);
DISPLAY 0.680851 (2610 3535);
PAINT MONO (2610 3535);
FORCEPROP 0 LASTPIN (2600 3575) $PN AL15
J 0
(2610 3585);
DISPLAY 0.680851 (2610 3585);
PAINT MONO (2610 3585);
FORCEPROP 0 LASTPIN (2600 3625) $PN AM14
J 0
(2610 3635);
DISPLAY 0.680851 (2610 3635);
PAINT MONO (2610 3635);
FORCEPROP 0 LASTPIN (2600 3675) $PN AR15
J 0
(2610 3685);
DISPLAY 0.680851 (2610 3685);
PAINT MONO (2610 3685);
FORCEPROP 0 LASTPIN (2600 3725) $PN AT14
J 0
(2610 3735);
DISPLAY 0.680851 (2610 3735);
PAINT MONO (2610 3735);
FORCEPROP 0 LASTPIN (2600 3775) $PN AW15
J 0
(2610 3785);
DISPLAY 0.680851 (2610 3785);
PAINT MONO (2610 3785);
FORCEPROP 0 LASTPIN (2600 3825) $PN AY14
J 0
(2610 3835);
DISPLAY 0.680851 (2610 3835);
PAINT MONO (2610 3835);
FORCEPROP 0 LASTPIN (2600 3875) $PN BC15
J 0
(2610 3885);
DISPLAY 0.680851 (2610 3885);
PAINT MONO (2610 3885);
FORCEPROP 1 LAST CDS_LMAN_SYM_OUTLINE -1050,950,1050,-950
J 0
(1400 3075);
DISPLAY 0.468085 (1400 3075);
PAINT GREEN (1400 3075);
DISPLAY INVISIBLE (1400 3075);
FORCEPROP 1 LAST NEEDS_NO_SIZE TRUE
J 0
(1400 3075);
DISPLAY 0.723404 (1400 3075);
PAINT GREEN (1400 3075);
DISPLAY INVISIBLE (1400 3075);
FORCEPROP 2 LAST CDS_LIB pure_quanta
J 0
(1400 3075);
DISPLAY INVISIBLE (1400 3075);
FORCEPROP 2 LAST CDS_LOCATION U2
J 0
(350 4350);
DISPLAY 1.021277 (350 4350);
DISPLAY INVISIBLE (350 4350);
FORCEPROP 0 LAST $SEC 17
J 0
(350 4350);
DISPLAY 0.680851 (350 4350);
PAINT MONO (350 4350);
DISPLAY INVISIBLE (350 4350);
FORCEPROP 2 LAST CDS_SEC 17
J 0
(350 4350);
DISPLAY 1.021277 (350 4350);
DISPLAY INVISIBLE (350 4350);
FORCEPROP 1 LAST PATH I37
J 0
(1400 3075);
DISPLAY 0.723404 (1400 3075);
PAINT GREEN (1400 3075);
DISPLAY INVISIBLE (1400 3075);
FORCEADD OFFPAGE..1
(-1525 3050);
FORCEPROP 2 LAST $XR1 139 
J 0
(-1897 3050);
DISPLAY 0.638298 (-1897 3050);
PAINT MONO (-1897 3050);
FORCEPROP 2 LAST $XR0 138 
J 0
(-1777 3050);
DISPLAY 0.638298 (-1777 3050);
PAINT MONO (-1777 3050);
FORCEPROP 2 LAST CDS_LIB standard
J 0
(-1525 3050);
PAINT MONO (-1525 3050);
DISPLAY INVISIBLE (-1525 3050);
FORCEPROP 1 LAST OFFPAGE TRUE
J 0
(-1200 2925);
DISPLAY 0.872340 (-1200 2925);
DISPLAY INVISIBLE (-1200 2925);
FORCEPROP 1 LAST COMMENT_BODY TRUE
J 0
(-1400 2950);
DISPLAY 0.872340 (-1400 2950);
PAINT GREEN (-1400 2950);
DISPLAY INVISIBLE (-1400 2950);
FORCEPROP 2 LAST PATH I402
J 0
(-1775 3100);
DISPLAY 1.021277 (-1775 3100);
DISPLAY INVISIBLE (-1775 3100);
FORCEADD OFFPAGE..1
(-1525 3900);
FORCEPROP 2 LAST $XR1 139 
J 0
(-1897 3900);
DISPLAY 0.638298 (-1897 3900);
PAINT MONO (-1897 3900);
FORCEPROP 2 LAST $XR0 138 
J 0
(-1777 3900);
DISPLAY 0.638298 (-1777 3900);
PAINT MONO (-1777 3900);
FORCEPROP 2 LAST CDS_LIB standard
J 0
(-1525 3900);
PAINT MONO (-1525 3900);
DISPLAY INVISIBLE (-1525 3900);
FORCEPROP 1 LAST OFFPAGE TRUE
J 0
(-1200 3775);
DISPLAY 0.872340 (-1200 3775);
DISPLAY INVISIBLE (-1200 3775);
FORCEPROP 1 LAST COMMENT_BODY TRUE
J 0
(-1400 3800);
DISPLAY 0.872340 (-1400 3800);
PAINT GREEN (-1400 3800);
DISPLAY INVISIBLE (-1400 3800);
FORCEPROP 2 LAST PATH I403
J 0
(-1775 3950);
DISPLAY 1.021277 (-1775 3950);
DISPLAY INVISIBLE (-1775 3950);
FORCEADD TAP..1
R 2
(-275 2275);
FORCEPROP 3 LASTPIN (-225 2275) SIG_NAME P5E_CPU0_PE0_RX_DN<0>
J 0
(-215 2285);
DISPLAY 0.659574 (-215 2285);
PAINT MONO (-215 2285);
DISPLAY INVISIBLE (-215 2285);
FORCEPROP 1 LASTPIN (-225 2275) BN 0
J 2
(-213 2283);
DISPLAY 0.680851 (-213 2283);
PAINT GREEN (-213 2283);
FORCEPROP 2 LAST CDS_LIB standard
J 0
(-275 2275);
DISPLAY INVISIBLE (-275 2275);
FORCEPROP 1 LAST BODY_TYPE PLUMBING
J 2
(-275 2325);
DISPLAY 0.872340 (-275 2325);
PAINT GREEN (-275 2325);
DISPLAY INVISIBLE (-275 2325);
FORCEPROP 1 LAST HDL_TAP TRUE
J 2
(-600 2150);
DISPLAY 0.872340 (-600 2150);
DISPLAY INVISIBLE (-600 2150);
FORCEPROP 1 LAST PATH I404
J 2
(-273 2275);
DISPLAY 0.872340 (-273 2275);
PAINT GREEN (-273 2275);
DISPLAY INVISIBLE (-273 2275);
FORCEADD TAP..1
R 2
(-275 2325);
FORCEPROP 3 LASTPIN (-225 2325) SIG_NAME P5E_CPU0_PE0_RX_DN<1>
J 0
(-215 2335);
DISPLAY 0.659574 (-215 2335);
PAINT MONO (-215 2335);
DISPLAY INVISIBLE (-215 2335);
FORCEPROP 1 LASTPIN (-225 2325) BN 1
J 2
(-213 2333);
DISPLAY 0.680851 (-213 2333);
PAINT GREEN (-213 2333);
FORCEPROP 2 LAST CDS_LIB standard
J 0
(-275 2325);
DISPLAY INVISIBLE (-275 2325);
FORCEPROP 1 LAST BODY_TYPE PLUMBING
J 2
(-275 2375);
DISPLAY 0.872340 (-275 2375);
PAINT GREEN (-275 2375);
DISPLAY INVISIBLE (-275 2375);
FORCEPROP 1 LAST HDL_TAP TRUE
J 2
(-600 2200);
DISPLAY 0.872340 (-600 2200);
DISPLAY INVISIBLE (-600 2200);
FORCEPROP 1 LAST PATH I405
J 2
(-273 2325);
DISPLAY 0.872340 (-273 2325);
PAINT GREEN (-273 2325);
DISPLAY INVISIBLE (-273 2325);
FORCEADD TAP..1
R 2
(-275 2425);
FORCEPROP 3 LASTPIN (-225 2425) SIG_NAME P5E_CPU0_PE0_RX_DN<3>
J 0
(-215 2435);
DISPLAY 0.659574 (-215 2435);
PAINT MONO (-215 2435);
DISPLAY INVISIBLE (-215 2435);
FORCEPROP 1 LASTPIN (-225 2425) BN 3
J 2
(-213 2433);
DISPLAY 0.680851 (-213 2433);
PAINT GREEN (-213 2433);
FORCEPROP 2 LAST CDS_LIB standard
J 0
(-275 2425);
DISPLAY INVISIBLE (-275 2425);
FORCEPROP 1 LAST BODY_TYPE PLUMBING
J 2
(-275 2475);
DISPLAY 0.872340 (-275 2475);
PAINT GREEN (-275 2475);
DISPLAY INVISIBLE (-275 2475);
FORCEPROP 1 LAST HDL_TAP TRUE
J 2
(-600 2300);
DISPLAY 0.872340 (-600 2300);
DISPLAY INVISIBLE (-600 2300);
FORCEPROP 1 LAST PATH I406
J 2
(-273 2425);
DISPLAY 0.872340 (-273 2425);
PAINT GREEN (-273 2425);
DISPLAY INVISIBLE (-273 2425);
FORCEADD TAP..1
R 2
(-275 2375);
FORCEPROP 3 LASTPIN (-225 2375) SIG_NAME P5E_CPU0_PE0_RX_DN<2>
J 0
(-215 2385);
DISPLAY 0.659574 (-215 2385);
PAINT MONO (-215 2385);
DISPLAY INVISIBLE (-215 2385);
FORCEPROP 1 LASTPIN (-225 2375) BN 2
J 2
(-213 2383);
DISPLAY 0.680851 (-213 2383);
PAINT GREEN (-213 2383);
FORCEPROP 2 LAST CDS_LIB standard
J 0
(-275 2375);
DISPLAY INVISIBLE (-275 2375);
FORCEPROP 1 LAST BODY_TYPE PLUMBING
J 2
(-275 2425);
DISPLAY 0.872340 (-275 2425);
PAINT GREEN (-275 2425);
DISPLAY INVISIBLE (-275 2425);
FORCEPROP 1 LAST HDL_TAP TRUE
J 2
(-600 2250);
DISPLAY 0.872340 (-600 2250);
DISPLAY INVISIBLE (-600 2250);
FORCEPROP 1 LAST PATH I407
J 2
(-273 2375);
DISPLAY 0.872340 (-273 2375);
PAINT GREEN (-273 2375);
DISPLAY INVISIBLE (-273 2375);
FORCEADD TAP..1
R 2
(-275 2525);
FORCEPROP 3 LASTPIN (-225 2525) SIG_NAME P5E_CPU0_PE0_RX_DN<5>
J 0
(-215 2535);
DISPLAY 0.659574 (-215 2535);
PAINT MONO (-215 2535);
DISPLAY INVISIBLE (-215 2535);
FORCEPROP 1 LASTPIN (-225 2525) BN 5
J 2
(-213 2533);
DISPLAY 0.680851 (-213 2533);
PAINT GREEN (-213 2533);
FORCEPROP 2 LAST CDS_LIB standard
J 0
(-275 2525);
DISPLAY INVISIBLE (-275 2525);
FORCEPROP 1 LAST BODY_TYPE PLUMBING
J 2
(-275 2575);
DISPLAY 0.872340 (-275 2575);
PAINT GREEN (-275 2575);
DISPLAY INVISIBLE (-275 2575);
FORCEPROP 1 LAST HDL_TAP TRUE
J 2
(-600 2400);
DISPLAY 0.872340 (-600 2400);
DISPLAY INVISIBLE (-600 2400);
FORCEPROP 1 LAST PATH I408
J 2
(-273 2525);
DISPLAY 0.872340 (-273 2525);
PAINT GREEN (-273 2525);
DISPLAY INVISIBLE (-273 2525);
FORCEADD TAP..1
R 2
(-275 2475);
FORCEPROP 3 LASTPIN (-225 2475) SIG_NAME P5E_CPU0_PE0_RX_DN<4>
J 0
(-215 2485);
DISPLAY 0.659574 (-215 2485);
PAINT MONO (-215 2485);
DISPLAY INVISIBLE (-215 2485);
FORCEPROP 1 LASTPIN (-225 2475) BN 4
J 2
(-213 2483);
DISPLAY 0.680851 (-213 2483);
PAINT GREEN (-213 2483);
FORCEPROP 2 LAST CDS_LIB standard
J 0
(-275 2475);
DISPLAY INVISIBLE (-275 2475);
FORCEPROP 1 LAST BODY_TYPE PLUMBING
J 2
(-275 2525);
DISPLAY 0.872340 (-275 2525);
PAINT GREEN (-275 2525);
DISPLAY INVISIBLE (-275 2525);
FORCEPROP 1 LAST HDL_TAP TRUE
J 2
(-600 2350);
DISPLAY 0.872340 (-600 2350);
DISPLAY INVISIBLE (-600 2350);
FORCEPROP 1 LAST PATH I409
J 2
(-273 2475);
DISPLAY 0.872340 (-273 2475);
PAINT GREEN (-273 2475);
DISPLAY INVISIBLE (-273 2475);
FORCEADD TAP..1
R 2
(-275 2575);
FORCEPROP 3 LASTPIN (-225 2575) SIG_NAME P5E_CPU0_PE0_RX_DN<6>
J 0
(-215 2585);
DISPLAY 0.659574 (-215 2585);
PAINT MONO (-215 2585);
DISPLAY INVISIBLE (-215 2585);
FORCEPROP 1 LASTPIN (-225 2575) BN 6
J 2
(-213 2583);
DISPLAY 0.680851 (-213 2583);
PAINT GREEN (-213 2583);
FORCEPROP 2 LAST CDS_LIB standard
J 0
(-275 2575);
DISPLAY INVISIBLE (-275 2575);
FORCEPROP 1 LAST BODY_TYPE PLUMBING
J 2
(-275 2625);
DISPLAY 0.872340 (-275 2625);
PAINT GREEN (-275 2625);
DISPLAY INVISIBLE (-275 2625);
FORCEPROP 1 LAST HDL_TAP TRUE
J 2
(-600 2450);
DISPLAY 0.872340 (-600 2450);
DISPLAY INVISIBLE (-600 2450);
FORCEPROP 1 LAST PATH I410
J 2
(-273 2575);
DISPLAY 0.872340 (-273 2575);
PAINT GREEN (-273 2575);
DISPLAY INVISIBLE (-273 2575);
FORCEADD TAP..1
R 2
(-275 2675);
FORCEPROP 3 LASTPIN (-225 2675) SIG_NAME P5E_CPU0_PE0_RX_DN<8>
J 0
(-215 2685);
DISPLAY 0.659574 (-215 2685);
PAINT MONO (-215 2685);
DISPLAY INVISIBLE (-215 2685);
FORCEPROP 1 LASTPIN (-225 2675) BN 8
J 2
(-213 2683);
DISPLAY 0.680851 (-213 2683);
PAINT GREEN (-213 2683);
FORCEPROP 2 LAST CDS_LIB standard
J 0
(-275 2675);
DISPLAY INVISIBLE (-275 2675);
FORCEPROP 1 LAST BODY_TYPE PLUMBING
J 2
(-275 2725);
DISPLAY 0.872340 (-275 2725);
PAINT GREEN (-275 2725);
DISPLAY INVISIBLE (-275 2725);
FORCEPROP 1 LAST HDL_TAP TRUE
J 2
(-600 2550);
DISPLAY 0.872340 (-600 2550);
DISPLAY INVISIBLE (-600 2550);
FORCEPROP 1 LAST PATH I411
J 2
(-273 2675);
DISPLAY 0.872340 (-273 2675);
PAINT GREEN (-273 2675);
DISPLAY INVISIBLE (-273 2675);
FORCEADD TAP..1
R 2
(-275 2625);
FORCEPROP 3 LASTPIN (-225 2625) SIG_NAME P5E_CPU0_PE0_RX_DN<7>
J 0
(-215 2635);
DISPLAY 0.659574 (-215 2635);
PAINT MONO (-215 2635);
DISPLAY INVISIBLE (-215 2635);
FORCEPROP 1 LASTPIN (-225 2625) BN 7
J 2
(-213 2633);
DISPLAY 0.680851 (-213 2633);
PAINT GREEN (-213 2633);
FORCEPROP 2 LAST CDS_LIB standard
J 0
(-275 2625);
DISPLAY INVISIBLE (-275 2625);
FORCEPROP 1 LAST BODY_TYPE PLUMBING
J 2
(-275 2675);
DISPLAY 0.872340 (-275 2675);
PAINT GREEN (-275 2675);
DISPLAY INVISIBLE (-275 2675);
FORCEPROP 1 LAST HDL_TAP TRUE
J 2
(-600 2500);
DISPLAY 0.872340 (-600 2500);
DISPLAY INVISIBLE (-600 2500);
FORCEPROP 1 LAST PATH I412
J 2
(-273 2625);
DISPLAY 0.872340 (-273 2625);
PAINT GREEN (-273 2625);
DISPLAY INVISIBLE (-273 2625);
FORCEADD TAP..1
R 2
(-275 2775);
FORCEPROP 3 LASTPIN (-225 2775) SIG_NAME P5E_CPU0_PE0_RX_DN<10>
J 0
(-215 2785);
DISPLAY 0.659574 (-215 2785);
PAINT MONO (-215 2785);
DISPLAY INVISIBLE (-215 2785);
FORCEPROP 1 LASTPIN (-225 2775) BN 10
J 2
(-213 2783);
DISPLAY 0.680851 (-213 2783);
PAINT GREEN (-213 2783);
FORCEPROP 2 LAST CDS_LIB standard
J 0
(-275 2775);
DISPLAY INVISIBLE (-275 2775);
FORCEPROP 1 LAST BODY_TYPE PLUMBING
J 2
(-275 2825);
DISPLAY 0.872340 (-275 2825);
PAINT GREEN (-275 2825);
DISPLAY INVISIBLE (-275 2825);
FORCEPROP 1 LAST HDL_TAP TRUE
J 2
(-600 2650);
DISPLAY 0.872340 (-600 2650);
DISPLAY INVISIBLE (-600 2650);
FORCEPROP 1 LAST PATH I413
J 2
(-273 2775);
DISPLAY 0.872340 (-273 2775);
PAINT GREEN (-273 2775);
DISPLAY INVISIBLE (-273 2775);
FORCEADD TAP..1
R 2
(-275 2725);
FORCEPROP 3 LASTPIN (-225 2725) SIG_NAME P5E_CPU0_PE0_RX_DN<9>
J 0
(-215 2735);
DISPLAY 0.659574 (-215 2735);
PAINT MONO (-215 2735);
DISPLAY INVISIBLE (-215 2735);
FORCEPROP 1 LASTPIN (-225 2725) BN 9
J 2
(-213 2733);
DISPLAY 0.680851 (-213 2733);
PAINT GREEN (-213 2733);
FORCEPROP 2 LAST CDS_LIB standard
J 0
(-275 2725);
DISPLAY INVISIBLE (-275 2725);
FORCEPROP 1 LAST BODY_TYPE PLUMBING
J 2
(-275 2775);
DISPLAY 0.872340 (-275 2775);
PAINT GREEN (-275 2775);
DISPLAY INVISIBLE (-275 2775);
FORCEPROP 1 LAST HDL_TAP TRUE
J 2
(-600 2600);
DISPLAY 0.872340 (-600 2600);
DISPLAY INVISIBLE (-600 2600);
FORCEPROP 1 LAST PATH I414
J 2
(-273 2725);
DISPLAY 0.872340 (-273 2725);
PAINT GREEN (-273 2725);
DISPLAY INVISIBLE (-273 2725);
FORCEADD TAP..1
R 2
(-275 2825);
FORCEPROP 3 LASTPIN (-225 2825) SIG_NAME P5E_CPU0_PE0_RX_DN<11>
J 0
(-215 2835);
DISPLAY 0.659574 (-215 2835);
PAINT MONO (-215 2835);
DISPLAY INVISIBLE (-215 2835);
FORCEPROP 1 LASTPIN (-225 2825) BN 11
J 2
(-213 2833);
DISPLAY 0.680851 (-213 2833);
PAINT GREEN (-213 2833);
FORCEPROP 2 LAST CDS_LIB standard
J 0
(-275 2825);
DISPLAY INVISIBLE (-275 2825);
FORCEPROP 1 LAST BODY_TYPE PLUMBING
J 2
(-275 2875);
DISPLAY 0.872340 (-275 2875);
PAINT GREEN (-275 2875);
DISPLAY INVISIBLE (-275 2875);
FORCEPROP 1 LAST HDL_TAP TRUE
J 2
(-600 2700);
DISPLAY 0.872340 (-600 2700);
DISPLAY INVISIBLE (-600 2700);
FORCEPROP 1 LAST PATH I415
J 2
(-273 2825);
DISPLAY 0.872340 (-273 2825);
PAINT GREEN (-273 2825);
DISPLAY INVISIBLE (-273 2825);
FORCEADD TAP..1
R 2
(-275 2925);
FORCEPROP 3 LASTPIN (-225 2925) SIG_NAME P5E_CPU0_PE0_RX_DN<13>
J 0
(-215 2935);
DISPLAY 0.659574 (-215 2935);
PAINT MONO (-215 2935);
DISPLAY INVISIBLE (-215 2935);
FORCEPROP 1 LASTPIN (-225 2925) BN 13
J 2
(-213 2933);
DISPLAY 0.680851 (-213 2933);
PAINT GREEN (-213 2933);
FORCEPROP 2 LAST CDS_LIB standard
J 0
(-275 2925);
DISPLAY INVISIBLE (-275 2925);
FORCEPROP 1 LAST BODY_TYPE PLUMBING
J 2
(-275 2975);
DISPLAY 0.872340 (-275 2975);
PAINT GREEN (-275 2975);
DISPLAY INVISIBLE (-275 2975);
FORCEPROP 1 LAST HDL_TAP TRUE
J 2
(-600 2800);
DISPLAY 0.872340 (-600 2800);
DISPLAY INVISIBLE (-600 2800);
FORCEPROP 1 LAST PATH I416
J 2
(-273 2925);
DISPLAY 0.872340 (-273 2925);
PAINT GREEN (-273 2925);
DISPLAY INVISIBLE (-273 2925);
FORCEADD TAP..1
R 2
(-275 2875);
FORCEPROP 3 LASTPIN (-225 2875) SIG_NAME P5E_CPU0_PE0_RX_DN<12>
J 0
(-215 2885);
DISPLAY 0.659574 (-215 2885);
PAINT MONO (-215 2885);
DISPLAY INVISIBLE (-215 2885);
FORCEPROP 1 LASTPIN (-225 2875) BN 12
J 2
(-213 2883);
DISPLAY 0.680851 (-213 2883);
PAINT GREEN (-213 2883);
FORCEPROP 2 LAST CDS_LIB standard
J 0
(-275 2875);
DISPLAY INVISIBLE (-275 2875);
FORCEPROP 1 LAST BODY_TYPE PLUMBING
J 2
(-275 2925);
DISPLAY 0.872340 (-275 2925);
PAINT GREEN (-275 2925);
DISPLAY INVISIBLE (-275 2925);
FORCEPROP 1 LAST HDL_TAP TRUE
J 2
(-600 2750);
DISPLAY 0.872340 (-600 2750);
DISPLAY INVISIBLE (-600 2750);
FORCEPROP 1 LAST PATH I417
J 2
(-273 2875);
DISPLAY 0.872340 (-273 2875);
PAINT GREEN (-273 2875);
DISPLAY INVISIBLE (-273 2875);
FORCEADD TAP..1
R 2
(-275 2975);
FORCEPROP 3 LASTPIN (-225 2975) SIG_NAME P5E_CPU0_PE0_RX_DN<14>
J 0
(-215 2985);
DISPLAY 0.659574 (-215 2985);
PAINT MONO (-215 2985);
DISPLAY INVISIBLE (-215 2985);
FORCEPROP 1 LASTPIN (-225 2975) BN 14
J 2
(-213 2983);
DISPLAY 0.680851 (-213 2983);
PAINT GREEN (-213 2983);
FORCEPROP 2 LAST CDS_LIB standard
J 0
(-275 2975);
DISPLAY INVISIBLE (-275 2975);
FORCEPROP 1 LAST BODY_TYPE PLUMBING
J 2
(-275 3025);
DISPLAY 0.872340 (-275 3025);
PAINT GREEN (-275 3025);
DISPLAY INVISIBLE (-275 3025);
FORCEPROP 1 LAST HDL_TAP TRUE
J 2
(-600 2850);
DISPLAY 0.872340 (-600 2850);
DISPLAY INVISIBLE (-600 2850);
FORCEPROP 1 LAST PATH I418
J 2
(-273 2975);
DISPLAY 0.872340 (-273 2975);
PAINT GREEN (-273 2975);
DISPLAY INVISIBLE (-273 2975);
FORCEADD TAP..1
R 2
(-275 3025);
FORCEPROP 3 LASTPIN (-225 3025) SIG_NAME P5E_CPU0_PE0_RX_DN<15>
J 0
(-215 3035);
DISPLAY 0.659574 (-215 3035);
PAINT MONO (-215 3035);
DISPLAY INVISIBLE (-215 3035);
FORCEPROP 1 LASTPIN (-225 3025) BN 15
J 2
(-213 3033);
DISPLAY 0.680851 (-213 3033);
PAINT GREEN (-213 3033);
FORCEPROP 2 LAST CDS_LIB standard
J 0
(-275 3025);
DISPLAY INVISIBLE (-275 3025);
FORCEPROP 1 LAST BODY_TYPE PLUMBING
J 2
(-275 3075);
DISPLAY 0.872340 (-275 3075);
PAINT GREEN (-275 3075);
DISPLAY INVISIBLE (-275 3075);
FORCEPROP 1 LAST HDL_TAP TRUE
J 2
(-600 2900);
DISPLAY 0.872340 (-600 2900);
DISPLAY INVISIBLE (-600 2900);
FORCEPROP 1 LAST PATH I419
J 2
(-273 3025);
DISPLAY 0.872340 (-273 3025);
PAINT GREEN (-273 3025);
DISPLAY INVISIBLE (-273 3025);
FORCEADD TAP..1
R 2
(-275 3125);
FORCEPROP 3 LASTPIN (-225 3125) SIG_NAME P5E_CPU0_PE0_RX_DP<0>
J 0
(-215 3135);
DISPLAY 0.659574 (-215 3135);
PAINT MONO (-215 3135);
DISPLAY INVISIBLE (-215 3135);
FORCEPROP 1 LASTPIN (-225 3125) BN 0
J 2
(-213 3133);
DISPLAY 0.680851 (-213 3133);
PAINT GREEN (-213 3133);
FORCEPROP 2 LAST CDS_LIB standard
J 0
(-275 3125);
DISPLAY INVISIBLE (-275 3125);
FORCEPROP 1 LAST BODY_TYPE PLUMBING
J 2
(-275 3175);
DISPLAY 0.872340 (-275 3175);
PAINT GREEN (-275 3175);
DISPLAY INVISIBLE (-275 3175);
FORCEPROP 1 LAST HDL_TAP TRUE
J 2
(-600 3000);
DISPLAY 0.872340 (-600 3000);
DISPLAY INVISIBLE (-600 3000);
FORCEPROP 1 LAST PATH I420
J 2
(-273 3125);
DISPLAY 0.872340 (-273 3125);
PAINT GREEN (-273 3125);
DISPLAY INVISIBLE (-273 3125);
FORCEADD TAP..1
R 2
(-275 3175);
FORCEPROP 3 LASTPIN (-225 3175) SIG_NAME P5E_CPU0_PE0_RX_DP<1>
J 0
(-215 3185);
DISPLAY 0.659574 (-215 3185);
PAINT MONO (-215 3185);
DISPLAY INVISIBLE (-215 3185);
FORCEPROP 1 LASTPIN (-225 3175) BN 1
J 2
(-213 3183);
DISPLAY 0.680851 (-213 3183);
PAINT GREEN (-213 3183);
FORCEPROP 2 LAST CDS_LIB standard
J 0
(-275 3175);
DISPLAY INVISIBLE (-275 3175);
FORCEPROP 1 LAST BODY_TYPE PLUMBING
J 2
(-275 3225);
DISPLAY 0.872340 (-275 3225);
PAINT GREEN (-275 3225);
DISPLAY INVISIBLE (-275 3225);
FORCEPROP 1 LAST HDL_TAP TRUE
J 2
(-600 3050);
DISPLAY 0.872340 (-600 3050);
DISPLAY INVISIBLE (-600 3050);
FORCEPROP 1 LAST PATH I421
J 2
(-273 3175);
DISPLAY 0.872340 (-273 3175);
PAINT GREEN (-273 3175);
DISPLAY INVISIBLE (-273 3175);
FORCEADD TAP..1
R 2
(-275 3225);
FORCEPROP 3 LASTPIN (-225 3225) SIG_NAME P5E_CPU0_PE0_RX_DP<2>
J 0
(-215 3235);
DISPLAY 0.659574 (-215 3235);
PAINT MONO (-215 3235);
DISPLAY INVISIBLE (-215 3235);
FORCEPROP 1 LASTPIN (-225 3225) BN 2
J 2
(-213 3233);
DISPLAY 0.680851 (-213 3233);
PAINT GREEN (-213 3233);
FORCEPROP 2 LAST CDS_LIB standard
J 0
(-275 3225);
DISPLAY INVISIBLE (-275 3225);
FORCEPROP 1 LAST BODY_TYPE PLUMBING
J 2
(-275 3275);
DISPLAY 0.872340 (-275 3275);
PAINT GREEN (-275 3275);
DISPLAY INVISIBLE (-275 3275);
FORCEPROP 1 LAST HDL_TAP TRUE
J 2
(-600 3100);
DISPLAY 0.872340 (-600 3100);
DISPLAY INVISIBLE (-600 3100);
FORCEPROP 1 LAST PATH I422
J 2
(-273 3225);
DISPLAY 0.872340 (-273 3225);
PAINT GREEN (-273 3225);
DISPLAY INVISIBLE (-273 3225);
FORCEADD TAP..1
R 2
(-275 3275);
FORCEPROP 3 LASTPIN (-225 3275) SIG_NAME P5E_CPU0_PE0_RX_DP<3>
J 0
(-215 3285);
DISPLAY 0.659574 (-215 3285);
PAINT MONO (-215 3285);
DISPLAY INVISIBLE (-215 3285);
FORCEPROP 1 LASTPIN (-225 3275) BN 3
J 2
(-213 3283);
DISPLAY 0.680851 (-213 3283);
PAINT GREEN (-213 3283);
FORCEPROP 2 LAST CDS_LIB standard
J 0
(-275 3275);
DISPLAY INVISIBLE (-275 3275);
FORCEPROP 1 LAST BODY_TYPE PLUMBING
J 2
(-275 3325);
DISPLAY 0.872340 (-275 3325);
PAINT GREEN (-275 3325);
DISPLAY INVISIBLE (-275 3325);
FORCEPROP 1 LAST HDL_TAP TRUE
J 2
(-600 3150);
DISPLAY 0.872340 (-600 3150);
DISPLAY INVISIBLE (-600 3150);
FORCEPROP 1 LAST PATH I423
J 2
(-273 3275);
DISPLAY 0.872340 (-273 3275);
PAINT GREEN (-273 3275);
DISPLAY INVISIBLE (-273 3275);
FORCEADD TAP..1
R 2
(-275 3325);
FORCEPROP 3 LASTPIN (-225 3325) SIG_NAME P5E_CPU0_PE0_RX_DP<4>
J 0
(-215 3335);
DISPLAY 0.659574 (-215 3335);
PAINT MONO (-215 3335);
DISPLAY INVISIBLE (-215 3335);
FORCEPROP 1 LASTPIN (-225 3325) BN 4
J 2
(-213 3333);
DISPLAY 0.680851 (-213 3333);
PAINT GREEN (-213 3333);
FORCEPROP 2 LAST CDS_LIB standard
J 0
(-275 3325);
DISPLAY INVISIBLE (-275 3325);
FORCEPROP 1 LAST BODY_TYPE PLUMBING
J 2
(-275 3375);
DISPLAY 0.872340 (-275 3375);
PAINT GREEN (-275 3375);
DISPLAY INVISIBLE (-275 3375);
FORCEPROP 1 LAST HDL_TAP TRUE
J 2
(-600 3200);
DISPLAY 0.872340 (-600 3200);
DISPLAY INVISIBLE (-600 3200);
FORCEPROP 1 LAST PATH I424
J 2
(-273 3325);
DISPLAY 0.872340 (-273 3325);
PAINT GREEN (-273 3325);
DISPLAY INVISIBLE (-273 3325);
FORCEADD TAP..1
R 2
(-275 3375);
FORCEPROP 3 LASTPIN (-225 3375) SIG_NAME P5E_CPU0_PE0_RX_DP<5>
J 0
(-215 3385);
DISPLAY 0.659574 (-215 3385);
PAINT MONO (-215 3385);
DISPLAY INVISIBLE (-215 3385);
FORCEPROP 1 LASTPIN (-225 3375) BN 5
J 2
(-213 3383);
DISPLAY 0.680851 (-213 3383);
PAINT GREEN (-213 3383);
FORCEPROP 2 LAST CDS_LIB standard
J 0
(-275 3375);
DISPLAY INVISIBLE (-275 3375);
FORCEPROP 1 LAST BODY_TYPE PLUMBING
J 2
(-275 3425);
DISPLAY 0.872340 (-275 3425);
PAINT GREEN (-275 3425);
DISPLAY INVISIBLE (-275 3425);
FORCEPROP 1 LAST HDL_TAP TRUE
J 2
(-600 3250);
DISPLAY 0.872340 (-600 3250);
DISPLAY INVISIBLE (-600 3250);
FORCEPROP 1 LAST PATH I425
J 2
(-273 3375);
DISPLAY 0.872340 (-273 3375);
PAINT GREEN (-273 3375);
DISPLAY INVISIBLE (-273 3375);
FORCEADD TAP..1
R 2
(-275 3425);
FORCEPROP 3 LASTPIN (-225 3425) SIG_NAME P5E_CPU0_PE0_RX_DP<6>
J 0
(-215 3435);
DISPLAY 0.659574 (-215 3435);
PAINT MONO (-215 3435);
DISPLAY INVISIBLE (-215 3435);
FORCEPROP 1 LASTPIN (-225 3425) BN 6
J 2
(-213 3433);
DISPLAY 0.680851 (-213 3433);
PAINT GREEN (-213 3433);
FORCEPROP 2 LAST CDS_LIB standard
J 0
(-275 3425);
DISPLAY INVISIBLE (-275 3425);
FORCEPROP 1 LAST BODY_TYPE PLUMBING
J 2
(-275 3475);
DISPLAY 0.872340 (-275 3475);
PAINT GREEN (-275 3475);
DISPLAY INVISIBLE (-275 3475);
FORCEPROP 1 LAST HDL_TAP TRUE
J 2
(-600 3300);
DISPLAY 0.872340 (-600 3300);
DISPLAY INVISIBLE (-600 3300);
FORCEPROP 1 LAST PATH I426
J 2
(-273 3425);
DISPLAY 0.872340 (-273 3425);
PAINT GREEN (-273 3425);
DISPLAY INVISIBLE (-273 3425);
FORCEADD TAP..1
R 2
(-275 3475);
FORCEPROP 3 LASTPIN (-225 3475) SIG_NAME P5E_CPU0_PE0_RX_DP<7>
J 0
(-215 3485);
DISPLAY 0.659574 (-215 3485);
PAINT MONO (-215 3485);
DISPLAY INVISIBLE (-215 3485);
FORCEPROP 1 LASTPIN (-225 3475) BN 7
J 2
(-213 3483);
DISPLAY 0.680851 (-213 3483);
PAINT GREEN (-213 3483);
FORCEPROP 2 LAST CDS_LIB standard
J 0
(-275 3475);
DISPLAY INVISIBLE (-275 3475);
FORCEPROP 1 LAST BODY_TYPE PLUMBING
J 2
(-275 3525);
DISPLAY 0.872340 (-275 3525);
PAINT GREEN (-275 3525);
DISPLAY INVISIBLE (-275 3525);
FORCEPROP 1 LAST HDL_TAP TRUE
J 2
(-600 3350);
DISPLAY 0.872340 (-600 3350);
DISPLAY INVISIBLE (-600 3350);
FORCEPROP 1 LAST PATH I427
J 2
(-273 3475);
DISPLAY 0.872340 (-273 3475);
PAINT GREEN (-273 3475);
DISPLAY INVISIBLE (-273 3475);
FORCEADD TAP..1
R 2
(-275 3525);
FORCEPROP 3 LASTPIN (-225 3525) SIG_NAME P5E_CPU0_PE0_RX_DP<8>
J 0
(-215 3535);
DISPLAY 0.659574 (-215 3535);
PAINT MONO (-215 3535);
DISPLAY INVISIBLE (-215 3535);
FORCEPROP 1 LASTPIN (-225 3525) BN 8
J 2
(-213 3533);
DISPLAY 0.680851 (-213 3533);
PAINT GREEN (-213 3533);
FORCEPROP 2 LAST CDS_LIB standard
J 0
(-275 3525);
DISPLAY INVISIBLE (-275 3525);
FORCEPROP 1 LAST BODY_TYPE PLUMBING
J 2
(-275 3575);
DISPLAY 0.872340 (-275 3575);
PAINT GREEN (-275 3575);
DISPLAY INVISIBLE (-275 3575);
FORCEPROP 1 LAST HDL_TAP TRUE
J 2
(-600 3400);
DISPLAY 0.872340 (-600 3400);
DISPLAY INVISIBLE (-600 3400);
FORCEPROP 1 LAST PATH I428
J 2
(-273 3525);
DISPLAY 0.872340 (-273 3525);
PAINT GREEN (-273 3525);
DISPLAY INVISIBLE (-273 3525);
FORCEADD TAP..1
R 2
(-275 3575);
FORCEPROP 3 LASTPIN (-225 3575) SIG_NAME P5E_CPU0_PE0_RX_DP<9>
J 0
(-215 3585);
DISPLAY 0.659574 (-215 3585);
PAINT MONO (-215 3585);
DISPLAY INVISIBLE (-215 3585);
FORCEPROP 1 LASTPIN (-225 3575) BN 9
J 2
(-213 3583);
DISPLAY 0.680851 (-213 3583);
PAINT GREEN (-213 3583);
FORCEPROP 2 LAST CDS_LIB standard
J 0
(-275 3575);
DISPLAY INVISIBLE (-275 3575);
FORCEPROP 1 LAST BODY_TYPE PLUMBING
J 2
(-275 3625);
DISPLAY 0.872340 (-275 3625);
PAINT GREEN (-275 3625);
DISPLAY INVISIBLE (-275 3625);
FORCEPROP 1 LAST HDL_TAP TRUE
J 2
(-600 3450);
DISPLAY 0.872340 (-600 3450);
DISPLAY INVISIBLE (-600 3450);
FORCEPROP 1 LAST PATH I429
J 2
(-273 3575);
DISPLAY 0.872340 (-273 3575);
PAINT GREEN (-273 3575);
DISPLAY INVISIBLE (-273 3575);
FORCEADD TAP..1
R 2
(-275 3625);
FORCEPROP 3 LASTPIN (-225 3625) SIG_NAME P5E_CPU0_PE0_RX_DP<10>
J 0
(-215 3635);
DISPLAY 0.659574 (-215 3635);
PAINT MONO (-215 3635);
DISPLAY INVISIBLE (-215 3635);
FORCEPROP 1 LASTPIN (-225 3625) BN 10
J 2
(-213 3633);
DISPLAY 0.680851 (-213 3633);
PAINT GREEN (-213 3633);
FORCEPROP 2 LAST CDS_LIB standard
J 0
(-275 3625);
DISPLAY INVISIBLE (-275 3625);
FORCEPROP 1 LAST BODY_TYPE PLUMBING
J 2
(-275 3675);
DISPLAY 0.872340 (-275 3675);
PAINT GREEN (-275 3675);
DISPLAY INVISIBLE (-275 3675);
FORCEPROP 1 LAST HDL_TAP TRUE
J 2
(-600 3500);
DISPLAY 0.872340 (-600 3500);
DISPLAY INVISIBLE (-600 3500);
FORCEPROP 1 LAST PATH I430
J 2
(-273 3625);
DISPLAY 0.872340 (-273 3625);
PAINT GREEN (-273 3625);
DISPLAY INVISIBLE (-273 3625);
FORCEADD TAP..1
R 2
(-275 3675);
FORCEPROP 3 LASTPIN (-225 3675) SIG_NAME P5E_CPU0_PE0_RX_DP<11>
J 0
(-215 3685);
DISPLAY 0.659574 (-215 3685);
PAINT MONO (-215 3685);
DISPLAY INVISIBLE (-215 3685);
FORCEPROP 1 LASTPIN (-225 3675) BN 11
J 2
(-213 3683);
DISPLAY 0.680851 (-213 3683);
PAINT GREEN (-213 3683);
FORCEPROP 2 LAST CDS_LIB standard
J 0
(-275 3675);
DISPLAY INVISIBLE (-275 3675);
FORCEPROP 1 LAST BODY_TYPE PLUMBING
J 2
(-275 3725);
DISPLAY 0.872340 (-275 3725);
PAINT GREEN (-275 3725);
DISPLAY INVISIBLE (-275 3725);
FORCEPROP 1 LAST HDL_TAP TRUE
J 2
(-600 3550);
DISPLAY 0.872340 (-600 3550);
DISPLAY INVISIBLE (-600 3550);
FORCEPROP 1 LAST PATH I431
J 2
(-273 3675);
DISPLAY 0.872340 (-273 3675);
PAINT GREEN (-273 3675);
DISPLAY INVISIBLE (-273 3675);
FORCEADD TAP..1
R 2
(-275 3725);
FORCEPROP 3 LASTPIN (-225 3725) SIG_NAME P5E_CPU0_PE0_RX_DP<12>
J 0
(-215 3735);
DISPLAY 0.659574 (-215 3735);
PAINT MONO (-215 3735);
DISPLAY INVISIBLE (-215 3735);
FORCEPROP 1 LASTPIN (-225 3725) BN 12
J 2
(-213 3733);
DISPLAY 0.680851 (-213 3733);
PAINT GREEN (-213 3733);
FORCEPROP 2 LAST CDS_LIB standard
J 0
(-275 3725);
DISPLAY INVISIBLE (-275 3725);
FORCEPROP 1 LAST BODY_TYPE PLUMBING
J 2
(-275 3775);
DISPLAY 0.872340 (-275 3775);
PAINT GREEN (-275 3775);
DISPLAY INVISIBLE (-275 3775);
FORCEPROP 1 LAST HDL_TAP TRUE
J 2
(-600 3600);
DISPLAY 0.872340 (-600 3600);
DISPLAY INVISIBLE (-600 3600);
FORCEPROP 1 LAST PATH I432
J 2
(-273 3725);
DISPLAY 0.872340 (-273 3725);
PAINT GREEN (-273 3725);
DISPLAY INVISIBLE (-273 3725);
FORCEADD TAP..1
R 2
(-275 3775);
FORCEPROP 3 LASTPIN (-225 3775) SIG_NAME P5E_CPU0_PE0_RX_DP<13>
J 0
(-215 3785);
DISPLAY 0.659574 (-215 3785);
PAINT MONO (-215 3785);
DISPLAY INVISIBLE (-215 3785);
FORCEPROP 1 LASTPIN (-225 3775) BN 13
J 2
(-213 3783);
DISPLAY 0.680851 (-213 3783);
PAINT GREEN (-213 3783);
FORCEPROP 2 LAST CDS_LIB standard
J 0
(-275 3775);
DISPLAY INVISIBLE (-275 3775);
FORCEPROP 1 LAST BODY_TYPE PLUMBING
J 2
(-275 3825);
DISPLAY 0.872340 (-275 3825);
PAINT GREEN (-275 3825);
DISPLAY INVISIBLE (-275 3825);
FORCEPROP 1 LAST HDL_TAP TRUE
J 2
(-600 3650);
DISPLAY 0.872340 (-600 3650);
DISPLAY INVISIBLE (-600 3650);
FORCEPROP 1 LAST PATH I433
J 2
(-273 3775);
DISPLAY 0.872340 (-273 3775);
PAINT GREEN (-273 3775);
DISPLAY INVISIBLE (-273 3775);
FORCEADD TAP..1
R 2
(-275 3825);
FORCEPROP 3 LASTPIN (-225 3825) SIG_NAME P5E_CPU0_PE0_RX_DP<14>
J 0
(-215 3835);
DISPLAY 0.659574 (-215 3835);
PAINT MONO (-215 3835);
DISPLAY INVISIBLE (-215 3835);
FORCEPROP 1 LASTPIN (-225 3825) BN 14
J 2
(-213 3833);
DISPLAY 0.680851 (-213 3833);
PAINT GREEN (-213 3833);
FORCEPROP 2 LAST CDS_LIB standard
J 0
(-275 3825);
DISPLAY INVISIBLE (-275 3825);
FORCEPROP 1 LAST BODY_TYPE PLUMBING
J 2
(-275 3875);
DISPLAY 0.872340 (-275 3875);
PAINT GREEN (-275 3875);
DISPLAY INVISIBLE (-275 3875);
FORCEPROP 1 LAST HDL_TAP TRUE
J 2
(-600 3700);
DISPLAY 0.872340 (-600 3700);
DISPLAY INVISIBLE (-600 3700);
FORCEPROP 1 LAST PATH I434
J 2
(-273 3825);
DISPLAY 0.872340 (-273 3825);
PAINT GREEN (-273 3825);
DISPLAY INVISIBLE (-273 3825);
FORCEADD TAP..1
R 2
(-275 3875);
FORCEPROP 3 LASTPIN (-225 3875) SIG_NAME P5E_CPU0_PE0_RX_DP<15>
J 0
(-215 3885);
DISPLAY 0.659574 (-215 3885);
PAINT MONO (-215 3885);
DISPLAY INVISIBLE (-215 3885);
FORCEPROP 1 LASTPIN (-225 3875) BN 15
J 2
(-213 3883);
DISPLAY 0.680851 (-213 3883);
PAINT GREEN (-213 3883);
FORCEPROP 2 LAST CDS_LIB standard
J 0
(-275 3875);
DISPLAY INVISIBLE (-275 3875);
FORCEPROP 1 LAST BODY_TYPE PLUMBING
J 2
(-275 3925);
DISPLAY 0.872340 (-275 3925);
PAINT GREEN (-275 3925);
DISPLAY INVISIBLE (-275 3925);
FORCEPROP 1 LAST HDL_TAP TRUE
J 2
(-600 3750);
DISPLAY 0.872340 (-600 3750);
DISPLAY INVISIBLE (-600 3750);
FORCEPROP 1 LAST PATH I435
J 2
(-273 3875);
DISPLAY 0.872340 (-273 3875);
PAINT GREEN (-273 3875);
DISPLAY INVISIBLE (-273 3875);
FORCEADD TAP..1
R 2
(-275 1125);
FORCEPROP 3 LASTPIN (-225 1125) SIG_NAME P5E_CPU0_PE1_RX_DP<15>
J 0
(-215 1135);
DISPLAY 0.659574 (-215 1135);
PAINT MONO (-215 1135);
DISPLAY INVISIBLE (-215 1135);
FORCEPROP 1 LASTPIN (-225 1125) BN 15
J 2
(-213 1133);
DISPLAY 0.680851 (-213 1133);
PAINT GREEN (-213 1133);
FORCEPROP 2 LAST CDS_LIB standard
J 0
(-275 1125);
DISPLAY INVISIBLE (-275 1125);
FORCEPROP 1 LAST BODY_TYPE PLUMBING
J 2
(-275 1175);
DISPLAY 0.872340 (-275 1175);
PAINT GREEN (-275 1175);
DISPLAY INVISIBLE (-275 1175);
FORCEPROP 1 LAST HDL_TAP TRUE
J 2
(-600 1000);
DISPLAY 0.872340 (-600 1000);
DISPLAY INVISIBLE (-600 1000);
FORCEPROP 1 LAST PATH I436
J 2
(-273 1125);
DISPLAY 0.872340 (-273 1125);
PAINT GREEN (-273 1125);
DISPLAY INVISIBLE (-273 1125);
FORCEADD TAP..1
R 2
(-275 1075);
FORCEPROP 3 LASTPIN (-225 1075) SIG_NAME P5E_CPU0_PE1_RX_DP<14>
J 0
(-215 1085);
DISPLAY 0.659574 (-215 1085);
PAINT MONO (-215 1085);
DISPLAY INVISIBLE (-215 1085);
FORCEPROP 1 LASTPIN (-225 1075) BN 14
J 2
(-213 1083);
DISPLAY 0.680851 (-213 1083);
PAINT GREEN (-213 1083);
FORCEPROP 2 LAST CDS_LIB standard
J 0
(-275 1075);
DISPLAY INVISIBLE (-275 1075);
FORCEPROP 1 LAST BODY_TYPE PLUMBING
J 2
(-275 1125);
DISPLAY 0.872340 (-275 1125);
PAINT GREEN (-275 1125);
DISPLAY INVISIBLE (-275 1125);
FORCEPROP 1 LAST HDL_TAP TRUE
J 2
(-600 950);
DISPLAY 0.872340 (-600 950);
DISPLAY INVISIBLE (-600 950);
FORCEPROP 1 LAST PATH I437
J 2
(-273 1075);
DISPLAY 0.872340 (-273 1075);
PAINT GREEN (-273 1075);
DISPLAY INVISIBLE (-273 1075);
FORCEADD TAP..1
R 2
(-275 1025);
FORCEPROP 3 LASTPIN (-225 1025) SIG_NAME P5E_CPU0_PE1_RX_DP<13>
J 0
(-215 1035);
DISPLAY 0.659574 (-215 1035);
PAINT MONO (-215 1035);
DISPLAY INVISIBLE (-215 1035);
FORCEPROP 1 LASTPIN (-225 1025) BN 13
J 2
(-213 1033);
DISPLAY 0.680851 (-213 1033);
PAINT GREEN (-213 1033);
FORCEPROP 2 LAST CDS_LIB standard
J 0
(-275 1025);
DISPLAY INVISIBLE (-275 1025);
FORCEPROP 1 LAST BODY_TYPE PLUMBING
J 2
(-275 1075);
DISPLAY 0.872340 (-275 1075);
PAINT GREEN (-275 1075);
DISPLAY INVISIBLE (-275 1075);
FORCEPROP 1 LAST HDL_TAP TRUE
J 2
(-600 900);
DISPLAY 0.872340 (-600 900);
DISPLAY INVISIBLE (-600 900);
FORCEPROP 1 LAST PATH I438
J 2
(-273 1025);
DISPLAY 0.872340 (-273 1025);
PAINT GREEN (-273 1025);
DISPLAY INVISIBLE (-273 1025);
FORCEADD TAP..1
R 2
(-275 975);
FORCEPROP 3 LASTPIN (-225 975) SIG_NAME P5E_CPU0_PE1_RX_DP<12>
J 0
(-215 985);
DISPLAY 0.659574 (-215 985);
PAINT MONO (-215 985);
DISPLAY INVISIBLE (-215 985);
FORCEPROP 1 LASTPIN (-225 975) BN 12
J 2
(-213 983);
DISPLAY 0.680851 (-213 983);
PAINT GREEN (-213 983);
FORCEPROP 2 LAST CDS_LIB standard
J 0
(-275 975);
DISPLAY INVISIBLE (-275 975);
FORCEPROP 1 LAST BODY_TYPE PLUMBING
J 2
(-275 1025);
DISPLAY 0.872340 (-275 1025);
PAINT GREEN (-275 1025);
DISPLAY INVISIBLE (-275 1025);
FORCEPROP 1 LAST HDL_TAP TRUE
J 2
(-600 850);
DISPLAY 0.872340 (-600 850);
DISPLAY INVISIBLE (-600 850);
FORCEPROP 1 LAST PATH I439
J 2
(-273 975);
DISPLAY 0.872340 (-273 975);
PAINT GREEN (-273 975);
DISPLAY INVISIBLE (-273 975);
FORCEADD TAP..1
R 2
(-275 925);
FORCEPROP 3 LASTPIN (-225 925) SIG_NAME P5E_CPU0_PE1_RX_DP<11>
J 0
(-215 935);
DISPLAY 0.659574 (-215 935);
PAINT MONO (-215 935);
DISPLAY INVISIBLE (-215 935);
FORCEPROP 1 LASTPIN (-225 925) BN 11
J 2
(-213 933);
DISPLAY 0.680851 (-213 933);
PAINT GREEN (-213 933);
FORCEPROP 2 LAST CDS_LIB standard
J 0
(-275 925);
DISPLAY INVISIBLE (-275 925);
FORCEPROP 1 LAST BODY_TYPE PLUMBING
J 2
(-275 975);
DISPLAY 0.872340 (-275 975);
PAINT GREEN (-275 975);
DISPLAY INVISIBLE (-275 975);
FORCEPROP 1 LAST HDL_TAP TRUE
J 2
(-600 800);
DISPLAY 0.872340 (-600 800);
DISPLAY INVISIBLE (-600 800);
FORCEPROP 1 LAST PATH I440
J 2
(-273 925);
DISPLAY 0.872340 (-273 925);
PAINT GREEN (-273 925);
DISPLAY INVISIBLE (-273 925);
FORCEADD TAP..1
R 2
(-275 875);
FORCEPROP 3 LASTPIN (-225 875) SIG_NAME P5E_CPU0_PE1_RX_DP<10>
J 0
(-215 885);
DISPLAY 0.659574 (-215 885);
PAINT MONO (-215 885);
DISPLAY INVISIBLE (-215 885);
FORCEPROP 1 LASTPIN (-225 875) BN 10
J 2
(-213 883);
DISPLAY 0.680851 (-213 883);
PAINT GREEN (-213 883);
FORCEPROP 2 LAST CDS_LIB standard
J 0
(-275 875);
DISPLAY INVISIBLE (-275 875);
FORCEPROP 1 LAST BODY_TYPE PLUMBING
J 2
(-275 925);
DISPLAY 0.872340 (-275 925);
PAINT GREEN (-275 925);
DISPLAY INVISIBLE (-275 925);
FORCEPROP 1 LAST HDL_TAP TRUE
J 2
(-600 750);
DISPLAY 0.872340 (-600 750);
DISPLAY INVISIBLE (-600 750);
FORCEPROP 1 LAST PATH I441
J 2
(-273 875);
DISPLAY 0.872340 (-273 875);
PAINT GREEN (-273 875);
DISPLAY INVISIBLE (-273 875);
FORCEADD TAP..1
R 2
(-275 825);
FORCEPROP 3 LASTPIN (-225 825) SIG_NAME P5E_CPU0_PE1_RX_DP<9>
J 0
(-215 835);
DISPLAY 0.659574 (-215 835);
PAINT MONO (-215 835);
DISPLAY INVISIBLE (-215 835);
FORCEPROP 1 LASTPIN (-225 825) BN 9
J 2
(-213 833);
DISPLAY 0.680851 (-213 833);
PAINT GREEN (-213 833);
FORCEPROP 2 LAST CDS_LIB standard
J 0
(-275 825);
DISPLAY INVISIBLE (-275 825);
FORCEPROP 1 LAST BODY_TYPE PLUMBING
J 2
(-275 875);
DISPLAY 0.872340 (-275 875);
PAINT GREEN (-275 875);
DISPLAY INVISIBLE (-275 875);
FORCEPROP 1 LAST HDL_TAP TRUE
J 2
(-600 700);
DISPLAY 0.872340 (-600 700);
DISPLAY INVISIBLE (-600 700);
FORCEPROP 1 LAST PATH I442
J 2
(-273 825);
DISPLAY 0.872340 (-273 825);
PAINT GREEN (-273 825);
DISPLAY INVISIBLE (-273 825);
FORCEADD TAP..1
R 2
(-275 725);
FORCEPROP 3 LASTPIN (-225 725) SIG_NAME P5E_CPU0_PE1_RX_DP<7>
J 0
(-215 735);
DISPLAY 0.659574 (-215 735);
PAINT MONO (-215 735);
DISPLAY INVISIBLE (-215 735);
FORCEPROP 1 LASTPIN (-225 725) BN 7
J 2
(-213 733);
DISPLAY 0.680851 (-213 733);
PAINT GREEN (-213 733);
FORCEPROP 2 LAST CDS_LIB standard
J 0
(-275 725);
DISPLAY INVISIBLE (-275 725);
FORCEPROP 1 LAST BODY_TYPE PLUMBING
J 2
(-275 775);
DISPLAY 0.872340 (-275 775);
PAINT GREEN (-275 775);
DISPLAY INVISIBLE (-275 775);
FORCEPROP 1 LAST HDL_TAP TRUE
J 2
(-600 600);
DISPLAY 0.872340 (-600 600);
DISPLAY INVISIBLE (-600 600);
FORCEPROP 1 LAST PATH I443
J 2
(-273 725);
DISPLAY 0.872340 (-273 725);
PAINT GREEN (-273 725);
DISPLAY INVISIBLE (-273 725);
FORCEADD TAP..1
R 2
(-275 775);
FORCEPROP 3 LASTPIN (-225 775) SIG_NAME P5E_CPU0_PE1_RX_DP<8>
J 0
(-215 785);
DISPLAY 0.659574 (-215 785);
PAINT MONO (-215 785);
DISPLAY INVISIBLE (-215 785);
FORCEPROP 1 LASTPIN (-225 775) BN 8
J 2
(-213 783);
DISPLAY 0.680851 (-213 783);
PAINT GREEN (-213 783);
FORCEPROP 2 LAST CDS_LIB standard
J 0
(-275 775);
DISPLAY INVISIBLE (-275 775);
FORCEPROP 1 LAST BODY_TYPE PLUMBING
J 2
(-275 825);
DISPLAY 0.872340 (-275 825);
PAINT GREEN (-275 825);
DISPLAY INVISIBLE (-275 825);
FORCEPROP 1 LAST HDL_TAP TRUE
J 2
(-600 650);
DISPLAY 0.872340 (-600 650);
DISPLAY INVISIBLE (-600 650);
FORCEPROP 1 LAST PATH I444
J 2
(-273 775);
DISPLAY 0.872340 (-273 775);
PAINT GREEN (-273 775);
DISPLAY INVISIBLE (-273 775);
FORCEADD TAP..1
R 2
(-275 675);
FORCEPROP 3 LASTPIN (-225 675) SIG_NAME P5E_CPU0_PE1_RX_DP<6>
J 0
(-215 685);
DISPLAY 0.659574 (-215 685);
PAINT MONO (-215 685);
DISPLAY INVISIBLE (-215 685);
FORCEPROP 1 LASTPIN (-225 675) BN 6
J 2
(-213 683);
DISPLAY 0.680851 (-213 683);
PAINT GREEN (-213 683);
FORCEPROP 2 LAST CDS_LIB standard
J 0
(-275 675);
DISPLAY INVISIBLE (-275 675);
FORCEPROP 1 LAST BODY_TYPE PLUMBING
J 2
(-275 725);
DISPLAY 0.872340 (-275 725);
PAINT GREEN (-275 725);
DISPLAY INVISIBLE (-275 725);
FORCEPROP 1 LAST HDL_TAP TRUE
J 2
(-600 550);
DISPLAY 0.872340 (-600 550);
DISPLAY INVISIBLE (-600 550);
FORCEPROP 1 LAST PATH I445
J 2
(-273 675);
DISPLAY 0.872340 (-273 675);
PAINT GREEN (-273 675);
DISPLAY INVISIBLE (-273 675);
FORCEADD TAP..1
R 2
(-275 625);
FORCEPROP 3 LASTPIN (-225 625) SIG_NAME P5E_CPU0_PE1_RX_DP<5>
J 0
(-215 635);
DISPLAY 0.659574 (-215 635);
PAINT MONO (-215 635);
DISPLAY INVISIBLE (-215 635);
FORCEPROP 1 LASTPIN (-225 625) BN 5
J 2
(-213 633);
DISPLAY 0.680851 (-213 633);
PAINT GREEN (-213 633);
FORCEPROP 2 LAST CDS_LIB standard
J 0
(-275 625);
DISPLAY INVISIBLE (-275 625);
FORCEPROP 1 LAST BODY_TYPE PLUMBING
J 2
(-275 675);
DISPLAY 0.872340 (-275 675);
PAINT GREEN (-275 675);
DISPLAY INVISIBLE (-275 675);
FORCEPROP 1 LAST HDL_TAP TRUE
J 2
(-600 500);
DISPLAY 0.872340 (-600 500);
DISPLAY INVISIBLE (-600 500);
FORCEPROP 1 LAST PATH I446
J 2
(-273 625);
DISPLAY 0.872340 (-273 625);
PAINT GREEN (-273 625);
DISPLAY INVISIBLE (-273 625);
FORCEADD TAP..1
R 2
(-275 575);
FORCEPROP 3 LASTPIN (-225 575) SIG_NAME P5E_CPU0_PE1_RX_DP<4>
J 0
(-215 585);
DISPLAY 0.659574 (-215 585);
PAINT MONO (-215 585);
DISPLAY INVISIBLE (-215 585);
FORCEPROP 1 LASTPIN (-225 575) BN 4
J 2
(-213 583);
DISPLAY 0.680851 (-213 583);
PAINT GREEN (-213 583);
FORCEPROP 2 LAST CDS_LIB standard
J 0
(-275 575);
DISPLAY INVISIBLE (-275 575);
FORCEPROP 1 LAST BODY_TYPE PLUMBING
J 2
(-275 625);
DISPLAY 0.872340 (-275 625);
PAINT GREEN (-275 625);
DISPLAY INVISIBLE (-275 625);
FORCEPROP 1 LAST HDL_TAP TRUE
J 2
(-600 450);
DISPLAY 0.872340 (-600 450);
DISPLAY INVISIBLE (-600 450);
FORCEPROP 1 LAST PATH I447
J 2
(-273 575);
DISPLAY 0.872340 (-273 575);
PAINT GREEN (-273 575);
DISPLAY INVISIBLE (-273 575);
FORCEADD TAP..1
R 2
(-275 475);
FORCEPROP 3 LASTPIN (-225 475) SIG_NAME P5E_CPU0_PE1_RX_DP<2>
J 0
(-215 485);
DISPLAY 0.659574 (-215 485);
PAINT MONO (-215 485);
DISPLAY INVISIBLE (-215 485);
FORCEPROP 1 LASTPIN (-225 475) BN 2
J 2
(-213 483);
DISPLAY 0.680851 (-213 483);
PAINT GREEN (-213 483);
FORCEPROP 2 LAST CDS_LIB standard
J 0
(-275 475);
DISPLAY INVISIBLE (-275 475);
FORCEPROP 1 LAST BODY_TYPE PLUMBING
J 2
(-275 525);
DISPLAY 0.872340 (-275 525);
PAINT GREEN (-275 525);
DISPLAY INVISIBLE (-275 525);
FORCEPROP 1 LAST HDL_TAP TRUE
J 2
(-600 350);
DISPLAY 0.872340 (-600 350);
DISPLAY INVISIBLE (-600 350);
FORCEPROP 1 LAST PATH I448
J 2
(-273 475);
DISPLAY 0.872340 (-273 475);
PAINT GREEN (-273 475);
DISPLAY INVISIBLE (-273 475);
FORCEADD TAP..1
R 2
(-275 525);
FORCEPROP 3 LASTPIN (-225 525) SIG_NAME P5E_CPU0_PE1_RX_DP<3>
J 0
(-215 535);
DISPLAY 0.659574 (-215 535);
PAINT MONO (-215 535);
DISPLAY INVISIBLE (-215 535);
FORCEPROP 1 LASTPIN (-225 525) BN 3
J 2
(-213 533);
DISPLAY 0.680851 (-213 533);
PAINT GREEN (-213 533);
FORCEPROP 2 LAST CDS_LIB standard
J 0
(-275 525);
DISPLAY INVISIBLE (-275 525);
FORCEPROP 1 LAST BODY_TYPE PLUMBING
J 2
(-275 575);
DISPLAY 0.872340 (-275 575);
PAINT GREEN (-275 575);
DISPLAY INVISIBLE (-275 575);
FORCEPROP 1 LAST HDL_TAP TRUE
J 2
(-600 400);
DISPLAY 0.872340 (-600 400);
DISPLAY INVISIBLE (-600 400);
FORCEPROP 1 LAST PATH I449
J 2
(-273 525);
DISPLAY 0.872340 (-273 525);
PAINT GREEN (-273 525);
DISPLAY INVISIBLE (-273 525);
FORCEADD TAP..1
R 2
(-275 425);
FORCEPROP 3 LASTPIN (-225 425) SIG_NAME P5E_CPU0_PE1_RX_DP<1>
J 0
(-215 435);
DISPLAY 0.659574 (-215 435);
PAINT MONO (-215 435);
DISPLAY INVISIBLE (-215 435);
FORCEPROP 1 LASTPIN (-225 425) BN 1
J 2
(-213 433);
DISPLAY 0.680851 (-213 433);
PAINT GREEN (-213 433);
FORCEPROP 2 LAST CDS_LIB standard
J 0
(-275 425);
DISPLAY INVISIBLE (-275 425);
FORCEPROP 1 LAST BODY_TYPE PLUMBING
J 2
(-275 475);
DISPLAY 0.872340 (-275 475);
PAINT GREEN (-275 475);
DISPLAY INVISIBLE (-275 475);
FORCEPROP 1 LAST HDL_TAP TRUE
J 2
(-600 300);
DISPLAY 0.872340 (-600 300);
DISPLAY INVISIBLE (-600 300);
FORCEPROP 1 LAST PATH I450
J 2
(-273 425);
DISPLAY 0.872340 (-273 425);
PAINT GREEN (-273 425);
DISPLAY INVISIBLE (-273 425);
FORCEADD TAP..1
R 2
(-275 375);
FORCEPROP 3 LASTPIN (-225 375) SIG_NAME P5E_CPU0_PE1_RX_DP<0>
J 0
(-215 385);
DISPLAY 0.659574 (-215 385);
PAINT MONO (-215 385);
DISPLAY INVISIBLE (-215 385);
FORCEPROP 1 LASTPIN (-225 375) BN 0
J 2
(-213 383);
DISPLAY 0.680851 (-213 383);
PAINT GREEN (-213 383);
FORCEPROP 2 LAST CDS_LIB standard
J 0
(-275 375);
DISPLAY INVISIBLE (-275 375);
FORCEPROP 1 LAST BODY_TYPE PLUMBING
J 2
(-275 425);
DISPLAY 0.872340 (-275 425);
PAINT GREEN (-275 425);
DISPLAY INVISIBLE (-275 425);
FORCEPROP 1 LAST HDL_TAP TRUE
J 2
(-600 250);
DISPLAY 0.872340 (-600 250);
DISPLAY INVISIBLE (-600 250);
FORCEPROP 1 LAST PATH I451
J 2
(-273 375);
DISPLAY 0.872340 (-273 375);
PAINT GREEN (-273 375);
DISPLAY INVISIBLE (-273 375);
FORCEADD TAP..1
R 2
(-275 275);
FORCEPROP 3 LASTPIN (-225 275) SIG_NAME P5E_CPU0_PE1_RX_DN<15>
J 0
(-215 285);
DISPLAY 0.659574 (-215 285);
PAINT MONO (-215 285);
DISPLAY INVISIBLE (-215 285);
FORCEPROP 1 LASTPIN (-225 275) BN 15
J 2
(-213 283);
DISPLAY 0.680851 (-213 283);
PAINT GREEN (-213 283);
FORCEPROP 2 LAST CDS_LIB standard
J 0
(-275 275);
DISPLAY INVISIBLE (-275 275);
FORCEPROP 1 LAST BODY_TYPE PLUMBING
J 2
(-275 325);
DISPLAY 0.872340 (-275 325);
PAINT GREEN (-275 325);
DISPLAY INVISIBLE (-275 325);
FORCEPROP 1 LAST HDL_TAP TRUE
J 2
(-600 150);
DISPLAY 0.872340 (-600 150);
DISPLAY INVISIBLE (-600 150);
FORCEPROP 1 LAST PATH I452
J 2
(-273 275);
DISPLAY 0.872340 (-273 275);
PAINT GREEN (-273 275);
DISPLAY INVISIBLE (-273 275);
FORCEADD TAP..1
R 2
(-275 175);
FORCEPROP 3 LASTPIN (-225 175) SIG_NAME P5E_CPU0_PE1_RX_DN<13>
J 0
(-215 185);
DISPLAY 0.659574 (-215 185);
PAINT MONO (-215 185);
DISPLAY INVISIBLE (-215 185);
FORCEPROP 1 LASTPIN (-225 175) BN 13
J 2
(-213 183);
DISPLAY 0.680851 (-213 183);
PAINT GREEN (-213 183);
FORCEPROP 2 LAST CDS_LIB standard
J 0
(-275 175);
DISPLAY INVISIBLE (-275 175);
FORCEPROP 1 LAST BODY_TYPE PLUMBING
J 2
(-275 225);
DISPLAY 0.872340 (-275 225);
PAINT GREEN (-275 225);
DISPLAY INVISIBLE (-275 225);
FORCEPROP 1 LAST HDL_TAP TRUE
J 2
(-600 50);
DISPLAY 0.872340 (-600 50);
DISPLAY INVISIBLE (-600 50);
FORCEPROP 1 LAST PATH I453
J 2
(-273 175);
DISPLAY 0.872340 (-273 175);
PAINT GREEN (-273 175);
DISPLAY INVISIBLE (-273 175);
FORCEADD TAP..1
R 2
(-275 225);
FORCEPROP 3 LASTPIN (-225 225) SIG_NAME P5E_CPU0_PE1_RX_DN<14>
J 0
(-215 235);
DISPLAY 0.659574 (-215 235);
PAINT MONO (-215 235);
DISPLAY INVISIBLE (-215 235);
FORCEPROP 1 LASTPIN (-225 225) BN 14
J 2
(-213 233);
DISPLAY 0.680851 (-213 233);
PAINT GREEN (-213 233);
FORCEPROP 2 LAST CDS_LIB standard
J 0
(-275 225);
DISPLAY INVISIBLE (-275 225);
FORCEPROP 1 LAST BODY_TYPE PLUMBING
J 2
(-275 275);
DISPLAY 0.872340 (-275 275);
PAINT GREEN (-275 275);
DISPLAY INVISIBLE (-275 275);
FORCEPROP 1 LAST HDL_TAP TRUE
J 2
(-600 100);
DISPLAY 0.872340 (-600 100);
DISPLAY INVISIBLE (-600 100);
FORCEPROP 1 LAST PATH I454
J 2
(-273 225);
DISPLAY 0.872340 (-273 225);
PAINT GREEN (-273 225);
DISPLAY INVISIBLE (-273 225);
FORCEADD TAP..1
R 2
(-275 125);
FORCEPROP 3 LASTPIN (-225 125) SIG_NAME P5E_CPU0_PE1_RX_DN<12>
J 0
(-215 135);
DISPLAY 0.659574 (-215 135);
PAINT MONO (-215 135);
DISPLAY INVISIBLE (-215 135);
FORCEPROP 1 LASTPIN (-225 125) BN 12
J 2
(-213 133);
DISPLAY 0.680851 (-213 133);
PAINT GREEN (-213 133);
FORCEPROP 2 LAST CDS_LIB standard
J 0
(-275 125);
DISPLAY INVISIBLE (-275 125);
FORCEPROP 1 LAST BODY_TYPE PLUMBING
J 2
(-275 175);
DISPLAY 0.872340 (-275 175);
PAINT GREEN (-275 175);
DISPLAY INVISIBLE (-275 175);
FORCEPROP 1 LAST HDL_TAP TRUE
J 2
(-600 0);
DISPLAY 0.872340 (-600 0);
DISPLAY INVISIBLE (-600 0);
FORCEPROP 1 LAST PATH I455
J 2
(-273 125);
DISPLAY 0.872340 (-273 125);
PAINT GREEN (-273 125);
DISPLAY INVISIBLE (-273 125);
FORCEADD TAP..1
R 2
(-275 75);
FORCEPROP 3 LASTPIN (-225 75) SIG_NAME P5E_CPU0_PE1_RX_DN<11>
J 0
(-215 85);
DISPLAY 0.659574 (-215 85);
PAINT MONO (-215 85);
DISPLAY INVISIBLE (-215 85);
FORCEPROP 1 LASTPIN (-225 75) BN 11
J 2
(-213 83);
DISPLAY 0.680851 (-213 83);
PAINT GREEN (-213 83);
FORCEPROP 2 LAST CDS_LIB standard
J 0
(-275 75);
DISPLAY INVISIBLE (-275 75);
FORCEPROP 1 LAST BODY_TYPE PLUMBING
J 2
(-275 125);
DISPLAY 0.872340 (-275 125);
PAINT GREEN (-275 125);
DISPLAY INVISIBLE (-275 125);
FORCEPROP 1 LAST HDL_TAP TRUE
J 2
(-600 -50);
DISPLAY 0.872340 (-600 -50);
DISPLAY INVISIBLE (-600 -50);
FORCEPROP 1 LAST PATH I456
J 2
(-273 75);
DISPLAY 0.872340 (-273 75);
PAINT GREEN (-273 75);
DISPLAY INVISIBLE (-273 75);
FORCEADD TAP..1
R 2
(-275 25);
FORCEPROP 3 LASTPIN (-225 25) SIG_NAME P5E_CPU0_PE1_RX_DN<10>
J 0
(-215 35);
DISPLAY 0.659574 (-215 35);
PAINT MONO (-215 35);
DISPLAY INVISIBLE (-215 35);
FORCEPROP 1 LASTPIN (-225 25) BN 10
J 2
(-213 33);
DISPLAY 0.680851 (-213 33);
PAINT GREEN (-213 33);
FORCEPROP 2 LAST CDS_LIB standard
J 0
(-275 25);
DISPLAY INVISIBLE (-275 25);
FORCEPROP 1 LAST BODY_TYPE PLUMBING
J 2
(-275 75);
DISPLAY 0.872340 (-275 75);
PAINT GREEN (-275 75);
DISPLAY INVISIBLE (-275 75);
FORCEPROP 1 LAST HDL_TAP TRUE
J 2
(-600 -100);
DISPLAY 0.872340 (-600 -100);
DISPLAY INVISIBLE (-600 -100);
FORCEPROP 1 LAST PATH I457
J 2
(-273 25);
DISPLAY 0.872340 (-273 25);
PAINT GREEN (-273 25);
DISPLAY INVISIBLE (-273 25);
FORCEADD TAP..1
R 2
(-275 -25);
FORCEPROP 3 LASTPIN (-225 -25) SIG_NAME P5E_CPU0_PE1_RX_DN<9>
J 0
(-215 -15);
DISPLAY 0.659574 (-215 -15);
PAINT MONO (-215 -15);
DISPLAY INVISIBLE (-215 -15);
FORCEPROP 1 LASTPIN (-225 -25) BN 9
J 2
(-213 -17);
DISPLAY 0.680851 (-213 -17);
PAINT GREEN (-213 -17);
FORCEPROP 2 LAST CDS_LIB standard
J 0
(-275 -25);
DISPLAY INVISIBLE (-275 -25);
FORCEPROP 1 LAST BODY_TYPE PLUMBING
J 2
(-275 25);
DISPLAY 0.872340 (-275 25);
PAINT GREEN (-275 25);
DISPLAY INVISIBLE (-275 25);
FORCEPROP 1 LAST HDL_TAP TRUE
J 2
(-600 -150);
DISPLAY 0.872340 (-600 -150);
DISPLAY INVISIBLE (-600 -150);
FORCEPROP 1 LAST PATH I458
J 2
(-273 -25);
DISPLAY 0.872340 (-273 -25);
PAINT GREEN (-273 -25);
DISPLAY INVISIBLE (-273 -25);
FORCEADD TAP..1
R 2
(-275 -75);
FORCEPROP 3 LASTPIN (-225 -75) SIG_NAME P5E_CPU0_PE1_RX_DN<8>
J 0
(-215 -65);
DISPLAY 0.659574 (-215 -65);
PAINT MONO (-215 -65);
DISPLAY INVISIBLE (-215 -65);
FORCEPROP 1 LASTPIN (-225 -75) BN 8
J 2
(-213 -67);
DISPLAY 0.680851 (-213 -67);
PAINT GREEN (-213 -67);
FORCEPROP 2 LAST CDS_LIB standard
J 0
(-275 -75);
DISPLAY INVISIBLE (-275 -75);
FORCEPROP 1 LAST BODY_TYPE PLUMBING
J 2
(-275 -25);
DISPLAY 0.872340 (-275 -25);
PAINT GREEN (-275 -25);
DISPLAY INVISIBLE (-275 -25);
FORCEPROP 1 LAST HDL_TAP TRUE
J 2
(-600 -200);
DISPLAY 0.872340 (-600 -200);
DISPLAY INVISIBLE (-600 -200);
FORCEPROP 1 LAST PATH I459
J 2
(-273 -75);
DISPLAY 0.872340 (-273 -75);
PAINT GREEN (-273 -75);
DISPLAY INVISIBLE (-273 -75);
FORCEADD TAP..1
R 2
(-275 -175);
FORCEPROP 3 LASTPIN (-225 -175) SIG_NAME P5E_CPU0_PE1_RX_DN<6>
J 0
(-215 -165);
DISPLAY 0.659574 (-215 -165);
PAINT MONO (-215 -165);
DISPLAY INVISIBLE (-215 -165);
FORCEPROP 1 LASTPIN (-225 -175) BN 6
J 2
(-213 -167);
DISPLAY 0.680851 (-213 -167);
PAINT GREEN (-213 -167);
FORCEPROP 2 LAST CDS_LIB standard
J 0
(-275 -175);
DISPLAY INVISIBLE (-275 -175);
FORCEPROP 1 LAST BODY_TYPE PLUMBING
J 2
(-275 -125);
DISPLAY 0.872340 (-275 -125);
PAINT GREEN (-275 -125);
DISPLAY INVISIBLE (-275 -125);
FORCEPROP 1 LAST HDL_TAP TRUE
J 2
(-600 -300);
DISPLAY 0.872340 (-600 -300);
DISPLAY INVISIBLE (-600 -300);
FORCEPROP 1 LAST PATH I460
J 2
(-273 -175);
DISPLAY 0.872340 (-273 -175);
PAINT GREEN (-273 -175);
DISPLAY INVISIBLE (-273 -175);
FORCEADD TAP..1
R 2
(-275 -125);
FORCEPROP 3 LASTPIN (-225 -125) SIG_NAME P5E_CPU0_PE1_RX_DN<7>
J 0
(-215 -115);
DISPLAY 0.659574 (-215 -115);
PAINT MONO (-215 -115);
DISPLAY INVISIBLE (-215 -115);
FORCEPROP 1 LASTPIN (-225 -125) BN 7
J 2
(-213 -117);
DISPLAY 0.680851 (-213 -117);
PAINT GREEN (-213 -117);
FORCEPROP 2 LAST CDS_LIB standard
J 0
(-275 -125);
DISPLAY INVISIBLE (-275 -125);
FORCEPROP 1 LAST BODY_TYPE PLUMBING
J 2
(-275 -75);
DISPLAY 0.872340 (-275 -75);
PAINT GREEN (-275 -75);
DISPLAY INVISIBLE (-275 -75);
FORCEPROP 1 LAST HDL_TAP TRUE
J 2
(-600 -250);
DISPLAY 0.872340 (-600 -250);
DISPLAY INVISIBLE (-600 -250);
FORCEPROP 1 LAST PATH I461
J 2
(-273 -125);
DISPLAY 0.872340 (-273 -125);
PAINT GREEN (-273 -125);
DISPLAY INVISIBLE (-273 -125);
FORCEADD TAP..1
R 2
(-275 -225);
FORCEPROP 3 LASTPIN (-225 -225) SIG_NAME P5E_CPU0_PE1_RX_DN<5>
J 0
(-215 -215);
DISPLAY 0.659574 (-215 -215);
PAINT MONO (-215 -215);
DISPLAY INVISIBLE (-215 -215);
FORCEPROP 1 LASTPIN (-225 -225) BN 5
J 2
(-213 -217);
DISPLAY 0.680851 (-213 -217);
PAINT GREEN (-213 -217);
FORCEPROP 2 LAST CDS_LIB standard
J 0
(-275 -225);
DISPLAY INVISIBLE (-275 -225);
FORCEPROP 1 LAST BODY_TYPE PLUMBING
J 2
(-275 -175);
DISPLAY 0.872340 (-275 -175);
PAINT GREEN (-275 -175);
DISPLAY INVISIBLE (-275 -175);
FORCEPROP 1 LAST HDL_TAP TRUE
J 2
(-600 -350);
DISPLAY 0.872340 (-600 -350);
DISPLAY INVISIBLE (-600 -350);
FORCEPROP 1 LAST PATH I462
J 2
(-273 -225);
DISPLAY 0.872340 (-273 -225);
PAINT GREEN (-273 -225);
DISPLAY INVISIBLE (-273 -225);
FORCEADD TAP..1
R 2
(-275 -275);
FORCEPROP 3 LASTPIN (-225 -275) SIG_NAME P5E_CPU0_PE1_RX_DN<4>
J 0
(-215 -265);
DISPLAY 0.659574 (-215 -265);
PAINT MONO (-215 -265);
DISPLAY INVISIBLE (-215 -265);
FORCEPROP 1 LASTPIN (-225 -275) BN 4
J 2
(-213 -267);
DISPLAY 0.680851 (-213 -267);
PAINT GREEN (-213 -267);
FORCEPROP 2 LAST CDS_LIB standard
J 0
(-275 -275);
DISPLAY INVISIBLE (-275 -275);
FORCEPROP 1 LAST BODY_TYPE PLUMBING
J 2
(-275 -225);
DISPLAY 0.872340 (-275 -225);
PAINT GREEN (-275 -225);
DISPLAY INVISIBLE (-275 -225);
FORCEPROP 1 LAST HDL_TAP TRUE
J 2
(-600 -400);
DISPLAY 0.872340 (-600 -400);
DISPLAY INVISIBLE (-600 -400);
FORCEPROP 1 LAST PATH I463
J 2
(-273 -275);
DISPLAY 0.872340 (-273 -275);
PAINT GREEN (-273 -275);
DISPLAY INVISIBLE (-273 -275);
FORCEADD TAP..1
R 2
(-275 -325);
FORCEPROP 3 LASTPIN (-225 -325) SIG_NAME P5E_CPU0_PE1_RX_DN<3>
J 0
(-215 -315);
DISPLAY 0.659574 (-215 -315);
PAINT MONO (-215 -315);
DISPLAY INVISIBLE (-215 -315);
FORCEPROP 1 LASTPIN (-225 -325) BN 3
J 2
(-213 -317);
DISPLAY 0.680851 (-213 -317);
PAINT GREEN (-213 -317);
FORCEPROP 2 LAST CDS_LIB standard
J 0
(-275 -325);
DISPLAY INVISIBLE (-275 -325);
FORCEPROP 1 LAST BODY_TYPE PLUMBING
J 2
(-275 -275);
DISPLAY 0.872340 (-275 -275);
PAINT GREEN (-275 -275);
DISPLAY INVISIBLE (-275 -275);
FORCEPROP 1 LAST HDL_TAP TRUE
J 2
(-600 -450);
DISPLAY 0.872340 (-600 -450);
DISPLAY INVISIBLE (-600 -450);
FORCEPROP 1 LAST PATH I464
J 2
(-273 -325);
DISPLAY 0.872340 (-273 -325);
PAINT GREEN (-273 -325);
DISPLAY INVISIBLE (-273 -325);
FORCEADD TAP..1
R 2
(-275 -425);
FORCEPROP 3 LASTPIN (-225 -425) SIG_NAME P5E_CPU0_PE1_RX_DN<1>
J 0
(-215 -415);
DISPLAY 0.659574 (-215 -415);
PAINT MONO (-215 -415);
DISPLAY INVISIBLE (-215 -415);
FORCEPROP 1 LASTPIN (-225 -425) BN 1
J 2
(-213 -417);
DISPLAY 0.680851 (-213 -417);
PAINT GREEN (-213 -417);
FORCEPROP 2 LAST CDS_LIB standard
J 0
(-275 -425);
DISPLAY INVISIBLE (-275 -425);
FORCEPROP 1 LAST BODY_TYPE PLUMBING
J 2
(-275 -375);
DISPLAY 0.872340 (-275 -375);
PAINT GREEN (-275 -375);
DISPLAY INVISIBLE (-275 -375);
FORCEPROP 1 LAST HDL_TAP TRUE
J 2
(-600 -550);
DISPLAY 0.872340 (-600 -550);
DISPLAY INVISIBLE (-600 -550);
FORCEPROP 1 LAST PATH I465
J 2
(-273 -425);
DISPLAY 0.872340 (-273 -425);
PAINT GREEN (-273 -425);
DISPLAY INVISIBLE (-273 -425);
FORCEADD TAP..1
R 2
(-275 -375);
FORCEPROP 3 LASTPIN (-225 -375) SIG_NAME P5E_CPU0_PE1_RX_DN<2>
J 0
(-215 -365);
DISPLAY 0.659574 (-215 -365);
PAINT MONO (-215 -365);
DISPLAY INVISIBLE (-215 -365);
FORCEPROP 1 LASTPIN (-225 -375) BN 2
J 2
(-213 -367);
DISPLAY 0.680851 (-213 -367);
PAINT GREEN (-213 -367);
FORCEPROP 2 LAST CDS_LIB standard
J 0
(-275 -375);
DISPLAY INVISIBLE (-275 -375);
FORCEPROP 1 LAST BODY_TYPE PLUMBING
J 2
(-275 -325);
DISPLAY 0.872340 (-275 -325);
PAINT GREEN (-275 -325);
DISPLAY INVISIBLE (-275 -325);
FORCEPROP 1 LAST HDL_TAP TRUE
J 2
(-600 -500);
DISPLAY 0.872340 (-600 -500);
DISPLAY INVISIBLE (-600 -500);
FORCEPROP 1 LAST PATH I466
J 2
(-273 -375);
DISPLAY 0.872340 (-273 -375);
PAINT GREEN (-273 -375);
DISPLAY INVISIBLE (-273 -375);
FORCEADD TAP..1
R 2
(-275 -475);
FORCEPROP 3 LASTPIN (-225 -475) SIG_NAME P5E_CPU0_PE1_RX_DN<0>
J 0
(-215 -465);
DISPLAY 0.659574 (-215 -465);
PAINT MONO (-215 -465);
DISPLAY INVISIBLE (-215 -465);
FORCEPROP 1 LASTPIN (-225 -475) BN 0
J 2
(-213 -467);
DISPLAY 0.680851 (-213 -467);
PAINT GREEN (-213 -467);
FORCEPROP 2 LAST CDS_LIB standard
J 0
(-275 -475);
DISPLAY INVISIBLE (-275 -475);
FORCEPROP 1 LAST BODY_TYPE PLUMBING
J 2
(-275 -425);
DISPLAY 0.872340 (-275 -425);
PAINT GREEN (-275 -425);
DISPLAY INVISIBLE (-275 -425);
FORCEPROP 1 LAST HDL_TAP TRUE
J 2
(-600 -600);
DISPLAY 0.872340 (-600 -600);
DISPLAY INVISIBLE (-600 -600);
FORCEPROP 1 LAST PATH I467
J 2
(-273 -475);
DISPLAY 0.872340 (-273 -475);
PAINT GREEN (-273 -475);
DISPLAY INVISIBLE (-273 -475);
FORCEADD OFFPAGE..1
(-1525 1150);
FORCEPROP 2 LAST $XR0 153 
J 0
(-1777 1150);
DISPLAY 0.638298 (-1777 1150);
PAINT MONO (-1777 1150);
FORCEPROP 2 LAST CDS_LIB standard
J 0
(-1525 1150);
PAINT MONO (-1525 1150);
DISPLAY INVISIBLE (-1525 1150);
FORCEPROP 1 LAST OFFPAGE TRUE
J 0
(-1200 1025);
DISPLAY 0.872340 (-1200 1025);
DISPLAY INVISIBLE (-1200 1025);
FORCEPROP 1 LAST COMMENT_BODY TRUE
J 0
(-1400 1050);
DISPLAY 0.872340 (-1400 1050);
PAINT GREEN (-1400 1050);
DISPLAY INVISIBLE (-1400 1050);
FORCEPROP 2 LAST PATH I468
J 0
(-1775 1200);
DISPLAY 1.021277 (-1775 1200);
DISPLAY INVISIBLE (-1775 1200);
FORCEADD OFFPAGE..1
(-1525 300);
FORCEPROP 2 LAST $XR0 153 
J 0
(-1777 300);
DISPLAY 0.638298 (-1777 300);
PAINT MONO (-1777 300);
FORCEPROP 2 LAST CDS_LIB standard
J 0
(-1525 300);
PAINT MONO (-1525 300);
DISPLAY INVISIBLE (-1525 300);
FORCEPROP 1 LAST OFFPAGE TRUE
J 0
(-1200 175);
DISPLAY 0.872340 (-1200 175);
DISPLAY INVISIBLE (-1200 175);
FORCEPROP 1 LAST COMMENT_BODY TRUE
J 0
(-1400 200);
DISPLAY 0.872340 (-1400 200);
PAINT GREEN (-1400 200);
DISPLAY INVISIBLE (-1400 200);
FORCEPROP 2 LAST PATH I469
J 0
(-1775 350);
DISPLAY 1.021277 (-1775 350);
DISPLAY INVISIBLE (-1775 350);
FORCEADD TAP..1
(3125 2375);
FORCEPROP 3 LASTPIN (3075 2375) SIG_NAME P5E_CPU0_PE0_TX_DN<2>
J 0
(3085 2385);
DISPLAY 0.659574 (3085 2385);
PAINT MONO (3085 2385);
DISPLAY INVISIBLE (3085 2385);
FORCEPROP 1 LASTPIN (3075 2375) BN 2
J 0
(3063 2383);
DISPLAY 0.680851 (3063 2383);
PAINT GREEN (3063 2383);
FORCEPROP 2 LAST CDS_LIB standard
J 0
(3125 2375);
PAINT MONO (3125 2375);
DISPLAY INVISIBLE (3125 2375);
FORCEPROP 1 LAST BODY_TYPE PLUMBING
J 0
(3125 2425);
DISPLAY 0.872340 (3125 2425);
PAINT GREEN (3125 2425);
DISPLAY INVISIBLE (3125 2425);
FORCEPROP 1 LAST HDL_TAP TRUE
J 0
(3450 2250);
DISPLAY 0.872340 (3450 2250);
DISPLAY INVISIBLE (3450 2250);
FORCEPROP 1 LAST PATH I470
J 0
(3123 2375);
DISPLAY 0.872340 (3123 2375);
PAINT GREEN (3123 2375);
DISPLAY INVISIBLE (3123 2375);
FORCEADD TAP..1
(3125 2325);
FORCEPROP 3 LASTPIN (3075 2325) SIG_NAME P5E_CPU0_PE0_TX_DN<1>
J 0
(3085 2335);
DISPLAY 0.659574 (3085 2335);
PAINT MONO (3085 2335);
DISPLAY INVISIBLE (3085 2335);
FORCEPROP 1 LASTPIN (3075 2325) BN 1
J 0
(3063 2333);
DISPLAY 0.680851 (3063 2333);
PAINT GREEN (3063 2333);
FORCEPROP 2 LAST CDS_LIB standard
J 0
(3125 2325);
PAINT MONO (3125 2325);
DISPLAY INVISIBLE (3125 2325);
FORCEPROP 1 LAST BODY_TYPE PLUMBING
J 0
(3125 2375);
DISPLAY 0.872340 (3125 2375);
PAINT GREEN (3125 2375);
DISPLAY INVISIBLE (3125 2375);
FORCEPROP 1 LAST HDL_TAP TRUE
J 0
(3450 2200);
DISPLAY 0.872340 (3450 2200);
DISPLAY INVISIBLE (3450 2200);
FORCEPROP 1 LAST PATH I471
J 0
(3123 2325);
DISPLAY 0.872340 (3123 2325);
PAINT GREEN (3123 2325);
DISPLAY INVISIBLE (3123 2325);
FORCEADD TAP..1
(3125 2275);
FORCEPROP 3 LASTPIN (3075 2275) SIG_NAME P5E_CPU0_PE0_TX_DN<0>
J 0
(3085 2285);
DISPLAY 0.659574 (3085 2285);
PAINT MONO (3085 2285);
DISPLAY INVISIBLE (3085 2285);
FORCEPROP 1 LASTPIN (3075 2275) BN 0
J 0
(3063 2283);
DISPLAY 0.680851 (3063 2283);
PAINT GREEN (3063 2283);
FORCEPROP 2 LAST CDS_LIB standard
J 0
(3125 2275);
PAINT MONO (3125 2275);
DISPLAY INVISIBLE (3125 2275);
FORCEPROP 1 LAST BODY_TYPE PLUMBING
J 0
(3125 2325);
DISPLAY 0.872340 (3125 2325);
PAINT GREEN (3125 2325);
DISPLAY INVISIBLE (3125 2325);
FORCEPROP 1 LAST HDL_TAP TRUE
J 0
(3450 2150);
DISPLAY 0.872340 (3450 2150);
DISPLAY INVISIBLE (3450 2150);
FORCEPROP 1 LAST PATH I472
J 0
(3123 2275);
DISPLAY 0.872340 (3123 2275);
PAINT GREEN (3123 2275);
DISPLAY INVISIBLE (3123 2275);
FORCEADD TAP..1
(3125 2475);
FORCEPROP 3 LASTPIN (3075 2475) SIG_NAME P5E_CPU0_PE0_TX_DN<4>
J 0
(3085 2485);
DISPLAY 0.659574 (3085 2485);
PAINT MONO (3085 2485);
DISPLAY INVISIBLE (3085 2485);
FORCEPROP 1 LASTPIN (3075 2475) BN 4
J 0
(3063 2483);
DISPLAY 0.680851 (3063 2483);
PAINT GREEN (3063 2483);
FORCEPROP 2 LAST CDS_LIB standard
J 0
(3125 2475);
PAINT MONO (3125 2475);
DISPLAY INVISIBLE (3125 2475);
FORCEPROP 1 LAST BODY_TYPE PLUMBING
J 0
(3125 2525);
DISPLAY 0.872340 (3125 2525);
PAINT GREEN (3125 2525);
DISPLAY INVISIBLE (3125 2525);
FORCEPROP 1 LAST HDL_TAP TRUE
J 0
(3450 2350);
DISPLAY 0.872340 (3450 2350);
DISPLAY INVISIBLE (3450 2350);
FORCEPROP 1 LAST PATH I473
J 0
(3123 2475);
DISPLAY 0.872340 (3123 2475);
PAINT GREEN (3123 2475);
DISPLAY INVISIBLE (3123 2475);
FORCEADD TAP..1
(3125 2425);
FORCEPROP 3 LASTPIN (3075 2425) SIG_NAME P5E_CPU0_PE0_TX_DN<3>
J 0
(3085 2435);
DISPLAY 0.659574 (3085 2435);
PAINT MONO (3085 2435);
DISPLAY INVISIBLE (3085 2435);
FORCEPROP 1 LASTPIN (3075 2425) BN 3
J 0
(3063 2433);
DISPLAY 0.680851 (3063 2433);
PAINT GREEN (3063 2433);
FORCEPROP 2 LAST CDS_LIB standard
J 0
(3125 2425);
PAINT MONO (3125 2425);
DISPLAY INVISIBLE (3125 2425);
FORCEPROP 1 LAST BODY_TYPE PLUMBING
J 0
(3125 2475);
DISPLAY 0.872340 (3125 2475);
PAINT GREEN (3125 2475);
DISPLAY INVISIBLE (3125 2475);
FORCEPROP 1 LAST HDL_TAP TRUE
J 0
(3450 2300);
DISPLAY 0.872340 (3450 2300);
DISPLAY INVISIBLE (3450 2300);
FORCEPROP 1 LAST PATH I474
J 0
(3123 2425);
DISPLAY 0.872340 (3123 2425);
PAINT GREEN (3123 2425);
DISPLAY INVISIBLE (3123 2425);
FORCEADD TAP..1
(3125 2625);
FORCEPROP 3 LASTPIN (3075 2625) SIG_NAME P5E_CPU0_PE0_TX_DN<7>
J 0
(3085 2635);
DISPLAY 0.659574 (3085 2635);
PAINT MONO (3085 2635);
DISPLAY INVISIBLE (3085 2635);
FORCEPROP 1 LASTPIN (3075 2625) BN 7
J 0
(3063 2633);
DISPLAY 0.680851 (3063 2633);
PAINT GREEN (3063 2633);
FORCEPROP 2 LAST CDS_LIB standard
J 0
(3125 2625);
PAINT MONO (3125 2625);
DISPLAY INVISIBLE (3125 2625);
FORCEPROP 1 LAST BODY_TYPE PLUMBING
J 0
(3125 2675);
DISPLAY 0.872340 (3125 2675);
PAINT GREEN (3125 2675);
DISPLAY INVISIBLE (3125 2675);
FORCEPROP 1 LAST HDL_TAP TRUE
J 0
(3450 2500);
DISPLAY 0.872340 (3450 2500);
DISPLAY INVISIBLE (3450 2500);
FORCEPROP 1 LAST PATH I475
J 0
(3123 2625);
DISPLAY 0.872340 (3123 2625);
PAINT GREEN (3123 2625);
DISPLAY INVISIBLE (3123 2625);
FORCEADD TAP..1
(3125 2575);
FORCEPROP 3 LASTPIN (3075 2575) SIG_NAME P5E_CPU0_PE0_TX_DN<6>
J 0
(3085 2585);
DISPLAY 0.659574 (3085 2585);
PAINT MONO (3085 2585);
DISPLAY INVISIBLE (3085 2585);
FORCEPROP 1 LASTPIN (3075 2575) BN 6
J 0
(3063 2583);
DISPLAY 0.680851 (3063 2583);
PAINT GREEN (3063 2583);
FORCEPROP 2 LAST CDS_LIB standard
J 0
(3125 2575);
PAINT MONO (3125 2575);
DISPLAY INVISIBLE (3125 2575);
FORCEPROP 1 LAST BODY_TYPE PLUMBING
J 0
(3125 2625);
DISPLAY 0.872340 (3125 2625);
PAINT GREEN (3125 2625);
DISPLAY INVISIBLE (3125 2625);
FORCEPROP 1 LAST HDL_TAP TRUE
J 0
(3450 2450);
DISPLAY 0.872340 (3450 2450);
DISPLAY INVISIBLE (3450 2450);
FORCEPROP 1 LAST PATH I476
J 0
(3123 2575);
DISPLAY 0.872340 (3123 2575);
PAINT GREEN (3123 2575);
DISPLAY INVISIBLE (3123 2575);
FORCEADD TAP..1
(3125 2525);
FORCEPROP 3 LASTPIN (3075 2525) SIG_NAME P5E_CPU0_PE0_TX_DN<5>
J 0
(3085 2535);
DISPLAY 0.659574 (3085 2535);
PAINT MONO (3085 2535);
DISPLAY INVISIBLE (3085 2535);
FORCEPROP 1 LASTPIN (3075 2525) BN 5
J 0
(3063 2533);
DISPLAY 0.680851 (3063 2533);
PAINT GREEN (3063 2533);
FORCEPROP 2 LAST CDS_LIB standard
J 0
(3125 2525);
PAINT MONO (3125 2525);
DISPLAY INVISIBLE (3125 2525);
FORCEPROP 1 LAST BODY_TYPE PLUMBING
J 0
(3125 2575);
DISPLAY 0.872340 (3125 2575);
PAINT GREEN (3125 2575);
DISPLAY INVISIBLE (3125 2575);
FORCEPROP 1 LAST HDL_TAP TRUE
J 0
(3450 2400);
DISPLAY 0.872340 (3450 2400);
DISPLAY INVISIBLE (3450 2400);
FORCEPROP 1 LAST PATH I477
J 0
(3123 2525);
DISPLAY 0.872340 (3123 2525);
PAINT GREEN (3123 2525);
DISPLAY INVISIBLE (3123 2525);
FORCEADD TAP..1
(3125 2675);
FORCEPROP 3 LASTPIN (3075 2675) SIG_NAME P5E_CPU0_PE0_TX_DN<8>
J 0
(3085 2685);
DISPLAY 0.659574 (3085 2685);
PAINT MONO (3085 2685);
DISPLAY INVISIBLE (3085 2685);
FORCEPROP 1 LASTPIN (3075 2675) BN 8
J 0
(3063 2683);
DISPLAY 0.680851 (3063 2683);
PAINT GREEN (3063 2683);
FORCEPROP 2 LAST CDS_LIB standard
J 0
(3125 2675);
PAINT MONO (3125 2675);
DISPLAY INVISIBLE (3125 2675);
FORCEPROP 1 LAST BODY_TYPE PLUMBING
J 0
(3125 2725);
DISPLAY 0.872340 (3125 2725);
PAINT GREEN (3125 2725);
DISPLAY INVISIBLE (3125 2725);
FORCEPROP 1 LAST HDL_TAP TRUE
J 0
(3450 2550);
DISPLAY 0.872340 (3450 2550);
DISPLAY INVISIBLE (3450 2550);
FORCEPROP 1 LAST PATH I478
J 0
(3123 2675);
DISPLAY 0.872340 (3123 2675);
PAINT GREEN (3123 2675);
DISPLAY INVISIBLE (3123 2675);
FORCEADD TAP..1
(3125 2725);
FORCEPROP 3 LASTPIN (3075 2725) SIG_NAME P5E_CPU0_PE0_TX_DN<9>
J 0
(3085 2735);
DISPLAY 0.659574 (3085 2735);
PAINT MONO (3085 2735);
DISPLAY INVISIBLE (3085 2735);
FORCEPROP 1 LASTPIN (3075 2725) BN 9
J 0
(3063 2733);
DISPLAY 0.680851 (3063 2733);
PAINT GREEN (3063 2733);
FORCEPROP 2 LAST CDS_LIB standard
J 0
(3125 2725);
DISPLAY INVISIBLE (3125 2725);
FORCEPROP 1 LAST BODY_TYPE PLUMBING
J 0
(3125 2775);
DISPLAY 0.872340 (3125 2775);
PAINT GREEN (3125 2775);
DISPLAY INVISIBLE (3125 2775);
FORCEPROP 1 LAST HDL_TAP TRUE
J 0
(3450 2600);
DISPLAY 0.872340 (3450 2600);
DISPLAY INVISIBLE (3450 2600);
FORCEPROP 1 LAST PATH I479
J 0
(3123 2725);
DISPLAY 0.872340 (3123 2725);
PAINT GREEN (3123 2725);
DISPLAY INVISIBLE (3123 2725);
FORCEADD TAP..1
(3125 2875);
FORCEPROP 3 LASTPIN (3075 2875) SIG_NAME P5E_CPU0_PE0_TX_DN<12>
J 0
(3085 2885);
DISPLAY 0.659574 (3085 2885);
PAINT MONO (3085 2885);
DISPLAY INVISIBLE (3085 2885);
FORCEPROP 1 LASTPIN (3075 2875) BN 12
J 0
(3063 2883);
DISPLAY 0.680851 (3063 2883);
PAINT GREEN (3063 2883);
FORCEPROP 2 LAST CDS_LIB standard
J 0
(3125 2875);
DISPLAY INVISIBLE (3125 2875);
FORCEPROP 1 LAST BODY_TYPE PLUMBING
J 0
(3125 2925);
DISPLAY 0.872340 (3125 2925);
PAINT GREEN (3125 2925);
DISPLAY INVISIBLE (3125 2925);
FORCEPROP 1 LAST HDL_TAP TRUE
J 0
(3450 2750);
DISPLAY 0.872340 (3450 2750);
DISPLAY INVISIBLE (3450 2750);
FORCEPROP 1 LAST PATH I480
J 0
(3123 2875);
DISPLAY 0.872340 (3123 2875);
PAINT GREEN (3123 2875);
DISPLAY INVISIBLE (3123 2875);
FORCEADD TAP..1
(3125 2775);
FORCEPROP 3 LASTPIN (3075 2775) SIG_NAME P5E_CPU0_PE0_TX_DN<10>
J 0
(3085 2785);
DISPLAY 0.659574 (3085 2785);
PAINT MONO (3085 2785);
DISPLAY INVISIBLE (3085 2785);
FORCEPROP 1 LASTPIN (3075 2775) BN 10
J 0
(3063 2783);
DISPLAY 0.680851 (3063 2783);
PAINT GREEN (3063 2783);
FORCEPROP 2 LAST CDS_LIB standard
J 0
(3125 2775);
DISPLAY INVISIBLE (3125 2775);
FORCEPROP 1 LAST BODY_TYPE PLUMBING
J 0
(3125 2825);
DISPLAY 0.872340 (3125 2825);
PAINT GREEN (3125 2825);
DISPLAY INVISIBLE (3125 2825);
FORCEPROP 1 LAST HDL_TAP TRUE
J 0
(3450 2650);
DISPLAY 0.872340 (3450 2650);
DISPLAY INVISIBLE (3450 2650);
FORCEPROP 1 LAST PATH I481
J 0
(3123 2775);
DISPLAY 0.872340 (3123 2775);
PAINT GREEN (3123 2775);
DISPLAY INVISIBLE (3123 2775);
FORCEADD TAP..1
(3125 2825);
FORCEPROP 3 LASTPIN (3075 2825) SIG_NAME P5E_CPU0_PE0_TX_DN<11>
J 0
(3085 2835);
DISPLAY 0.659574 (3085 2835);
PAINT MONO (3085 2835);
DISPLAY INVISIBLE (3085 2835);
FORCEPROP 1 LASTPIN (3075 2825) BN 11
J 0
(3063 2833);
DISPLAY 0.680851 (3063 2833);
PAINT GREEN (3063 2833);
FORCEPROP 2 LAST CDS_LIB standard
J 0
(3125 2825);
DISPLAY INVISIBLE (3125 2825);
FORCEPROP 1 LAST BODY_TYPE PLUMBING
J 0
(3125 2875);
DISPLAY 0.872340 (3125 2875);
PAINT GREEN (3125 2875);
DISPLAY INVISIBLE (3125 2875);
FORCEPROP 1 LAST HDL_TAP TRUE
J 0
(3450 2700);
DISPLAY 0.872340 (3450 2700);
DISPLAY INVISIBLE (3450 2700);
FORCEPROP 1 LAST PATH I482
J 0
(3123 2825);
DISPLAY 0.872340 (3123 2825);
PAINT GREEN (3123 2825);
DISPLAY INVISIBLE (3123 2825);
FORCEADD TAP..1
(3125 2925);
FORCEPROP 3 LASTPIN (3075 2925) SIG_NAME P5E_CPU0_PE0_TX_DN<13>
J 0
(3085 2935);
DISPLAY 0.659574 (3085 2935);
PAINT MONO (3085 2935);
DISPLAY INVISIBLE (3085 2935);
FORCEPROP 1 LASTPIN (3075 2925) BN 13
J 0
(3063 2933);
DISPLAY 0.680851 (3063 2933);
PAINT GREEN (3063 2933);
FORCEPROP 2 LAST CDS_LIB standard
J 0
(3125 2925);
DISPLAY INVISIBLE (3125 2925);
FORCEPROP 1 LAST BODY_TYPE PLUMBING
J 0
(3125 2975);
DISPLAY 0.872340 (3125 2975);
PAINT GREEN (3125 2975);
DISPLAY INVISIBLE (3125 2975);
FORCEPROP 1 LAST HDL_TAP TRUE
J 0
(3450 2800);
DISPLAY 0.872340 (3450 2800);
DISPLAY INVISIBLE (3450 2800);
FORCEPROP 1 LAST PATH I483
J 0
(3123 2925);
DISPLAY 0.872340 (3123 2925);
PAINT GREEN (3123 2925);
DISPLAY INVISIBLE (3123 2925);
FORCEADD TAP..1
(3125 2975);
FORCEPROP 3 LASTPIN (3075 2975) SIG_NAME P5E_CPU0_PE0_TX_DN<14>
J 0
(3085 2985);
DISPLAY 0.659574 (3085 2985);
PAINT MONO (3085 2985);
DISPLAY INVISIBLE (3085 2985);
FORCEPROP 1 LASTPIN (3075 2975) BN 14
J 0
(3063 2983);
DISPLAY 0.680851 (3063 2983);
PAINT GREEN (3063 2983);
FORCEPROP 2 LAST CDS_LIB standard
J 0
(3125 2975);
DISPLAY INVISIBLE (3125 2975);
FORCEPROP 1 LAST BODY_TYPE PLUMBING
J 0
(3125 3025);
DISPLAY 0.872340 (3125 3025);
PAINT GREEN (3125 3025);
DISPLAY INVISIBLE (3125 3025);
FORCEPROP 1 LAST HDL_TAP TRUE
J 0
(3450 2850);
DISPLAY 0.872340 (3450 2850);
DISPLAY INVISIBLE (3450 2850);
FORCEPROP 1 LAST PATH I484
J 0
(3123 2975);
DISPLAY 0.872340 (3123 2975);
PAINT GREEN (3123 2975);
DISPLAY INVISIBLE (3123 2975);
FORCEADD TAP..1
(3125 3025);
FORCEPROP 3 LASTPIN (3075 3025) SIG_NAME P5E_CPU0_PE0_TX_DN<15>
J 0
(3085 3035);
DISPLAY 0.659574 (3085 3035);
PAINT MONO (3085 3035);
DISPLAY INVISIBLE (3085 3035);
FORCEPROP 1 LASTPIN (3075 3025) BN 15
J 0
(3063 3033);
DISPLAY 0.680851 (3063 3033);
PAINT GREEN (3063 3033);
FORCEPROP 2 LAST CDS_LIB standard
J 0
(3125 3025);
DISPLAY INVISIBLE (3125 3025);
FORCEPROP 1 LAST BODY_TYPE PLUMBING
J 0
(3125 3075);
DISPLAY 0.872340 (3125 3075);
PAINT GREEN (3125 3075);
DISPLAY INVISIBLE (3125 3075);
FORCEPROP 1 LAST HDL_TAP TRUE
J 0
(3450 2900);
DISPLAY 0.872340 (3450 2900);
DISPLAY INVISIBLE (3450 2900);
FORCEPROP 1 LAST PATH I485
J 0
(3123 3025);
DISPLAY 0.872340 (3123 3025);
PAINT GREEN (3123 3025);
DISPLAY INVISIBLE (3123 3025);
FORCEADD TAP..1
(3125 3125);
FORCEPROP 3 LASTPIN (3075 3125) SIG_NAME P5E_CPU0_PE0_TX_DP<0>
J 0
(3085 3135);
DISPLAY 0.659574 (3085 3135);
PAINT MONO (3085 3135);
DISPLAY INVISIBLE (3085 3135);
FORCEPROP 1 LASTPIN (3075 3125) BN 0
J 0
(3063 3133);
DISPLAY 0.680851 (3063 3133);
PAINT GREEN (3063 3133);
FORCEPROP 2 LAST CDS_LIB standard
J 0
(3125 3125);
PAINT MONO (3125 3125);
DISPLAY INVISIBLE (3125 3125);
FORCEPROP 1 LAST BODY_TYPE PLUMBING
J 0
(3125 3175);
DISPLAY 0.872340 (3125 3175);
PAINT GREEN (3125 3175);
DISPLAY INVISIBLE (3125 3175);
FORCEPROP 1 LAST HDL_TAP TRUE
J 0
(3450 3000);
DISPLAY 0.872340 (3450 3000);
DISPLAY INVISIBLE (3450 3000);
FORCEPROP 1 LAST PATH I486
J 0
(3123 3125);
DISPLAY 0.872340 (3123 3125);
PAINT GREEN (3123 3125);
DISPLAY INVISIBLE (3123 3125);
FORCEADD TAP..1
(3125 3275);
FORCEPROP 3 LASTPIN (3075 3275) SIG_NAME P5E_CPU0_PE0_TX_DP<3>
J 0
(3085 3285);
DISPLAY 0.659574 (3085 3285);
PAINT MONO (3085 3285);
DISPLAY INVISIBLE (3085 3285);
FORCEPROP 1 LASTPIN (3075 3275) BN 3
J 0
(3063 3283);
DISPLAY 0.680851 (3063 3283);
PAINT GREEN (3063 3283);
FORCEPROP 2 LAST CDS_LIB standard
J 0
(3125 3275);
PAINT MONO (3125 3275);
DISPLAY INVISIBLE (3125 3275);
FORCEPROP 1 LAST BODY_TYPE PLUMBING
J 0
(3125 3325);
DISPLAY 0.872340 (3125 3325);
PAINT GREEN (3125 3325);
DISPLAY INVISIBLE (3125 3325);
FORCEPROP 1 LAST HDL_TAP TRUE
J 0
(3450 3150);
DISPLAY 0.872340 (3450 3150);
DISPLAY INVISIBLE (3450 3150);
FORCEPROP 1 LAST PATH I487
J 0
(3123 3275);
DISPLAY 0.872340 (3123 3275);
PAINT GREEN (3123 3275);
DISPLAY INVISIBLE (3123 3275);
FORCEADD TAP..1
(3125 3175);
FORCEPROP 3 LASTPIN (3075 3175) SIG_NAME P5E_CPU0_PE0_TX_DP<1>
J 0
(3085 3185);
DISPLAY 0.659574 (3085 3185);
PAINT MONO (3085 3185);
DISPLAY INVISIBLE (3085 3185);
FORCEPROP 1 LASTPIN (3075 3175) BN 1
J 0
(3063 3183);
DISPLAY 0.680851 (3063 3183);
PAINT GREEN (3063 3183);
FORCEPROP 2 LAST CDS_LIB standard
J 0
(3125 3175);
PAINT MONO (3125 3175);
DISPLAY INVISIBLE (3125 3175);
FORCEPROP 1 LAST BODY_TYPE PLUMBING
J 0
(3125 3225);
DISPLAY 0.872340 (3125 3225);
PAINT GREEN (3125 3225);
DISPLAY INVISIBLE (3125 3225);
FORCEPROP 1 LAST HDL_TAP TRUE
J 0
(3450 3050);
DISPLAY 0.872340 (3450 3050);
DISPLAY INVISIBLE (3450 3050);
FORCEPROP 1 LAST PATH I488
J 0
(3123 3175);
DISPLAY 0.872340 (3123 3175);
PAINT GREEN (3123 3175);
DISPLAY INVISIBLE (3123 3175);
FORCEADD TAP..1
(3125 3225);
FORCEPROP 3 LASTPIN (3075 3225) SIG_NAME P5E_CPU0_PE0_TX_DP<2>
J 0
(3085 3235);
DISPLAY 0.659574 (3085 3235);
PAINT MONO (3085 3235);
DISPLAY INVISIBLE (3085 3235);
FORCEPROP 1 LASTPIN (3075 3225) BN 2
J 0
(3063 3233);
DISPLAY 0.680851 (3063 3233);
PAINT GREEN (3063 3233);
FORCEPROP 2 LAST CDS_LIB standard
J 0
(3125 3225);
PAINT MONO (3125 3225);
DISPLAY INVISIBLE (3125 3225);
FORCEPROP 1 LAST BODY_TYPE PLUMBING
J 0
(3125 3275);
DISPLAY 0.872340 (3125 3275);
PAINT GREEN (3125 3275);
DISPLAY INVISIBLE (3125 3275);
FORCEPROP 1 LAST HDL_TAP TRUE
J 0
(3450 3100);
DISPLAY 0.872340 (3450 3100);
DISPLAY INVISIBLE (3450 3100);
FORCEPROP 1 LAST PATH I489
J 0
(3123 3225);
DISPLAY 0.872340 (3123 3225);
PAINT GREEN (3123 3225);
DISPLAY INVISIBLE (3123 3225);
FORCEADD TAP..1
(3125 3375);
FORCEPROP 3 LASTPIN (3075 3375) SIG_NAME P5E_CPU0_PE0_TX_DP<5>
J 0
(3085 3385);
DISPLAY 0.659574 (3085 3385);
PAINT MONO (3085 3385);
DISPLAY INVISIBLE (3085 3385);
FORCEPROP 1 LASTPIN (3075 3375) BN 5
J 0
(3063 3383);
DISPLAY 0.680851 (3063 3383);
PAINT GREEN (3063 3383);
FORCEPROP 2 LAST CDS_LIB standard
J 0
(3125 3375);
PAINT MONO (3125 3375);
DISPLAY INVISIBLE (3125 3375);
FORCEPROP 1 LAST BODY_TYPE PLUMBING
J 0
(3125 3425);
DISPLAY 0.872340 (3125 3425);
PAINT GREEN (3125 3425);
DISPLAY INVISIBLE (3125 3425);
FORCEPROP 1 LAST HDL_TAP TRUE
J 0
(3450 3250);
DISPLAY 0.872340 (3450 3250);
DISPLAY INVISIBLE (3450 3250);
FORCEPROP 1 LAST PATH I490
J 0
(3123 3375);
DISPLAY 0.872340 (3123 3375);
PAINT GREEN (3123 3375);
DISPLAY INVISIBLE (3123 3375);
FORCEADD TAP..1
(3125 3325);
FORCEPROP 3 LASTPIN (3075 3325) SIG_NAME P5E_CPU0_PE0_TX_DP<4>
J 0
(3085 3335);
DISPLAY 0.659574 (3085 3335);
PAINT MONO (3085 3335);
DISPLAY INVISIBLE (3085 3335);
FORCEPROP 1 LASTPIN (3075 3325) BN 4
J 0
(3063 3333);
DISPLAY 0.680851 (3063 3333);
PAINT GREEN (3063 3333);
FORCEPROP 2 LAST CDS_LIB standard
J 0
(3125 3325);
PAINT MONO (3125 3325);
DISPLAY INVISIBLE (3125 3325);
FORCEPROP 1 LAST BODY_TYPE PLUMBING
J 0
(3125 3375);
DISPLAY 0.872340 (3125 3375);
PAINT GREEN (3125 3375);
DISPLAY INVISIBLE (3125 3375);
FORCEPROP 1 LAST HDL_TAP TRUE
J 0
(3450 3200);
DISPLAY 0.872340 (3450 3200);
DISPLAY INVISIBLE (3450 3200);
FORCEPROP 1 LAST PATH I491
J 0
(3123 3325);
DISPLAY 0.872340 (3123 3325);
PAINT GREEN (3123 3325);
DISPLAY INVISIBLE (3123 3325);
FORCEADD TAP..1
(3125 3525);
FORCEPROP 3 LASTPIN (3075 3525) SIG_NAME P5E_CPU0_PE0_TX_DP<8>
J 0
(3085 3535);
DISPLAY 0.659574 (3085 3535);
PAINT MONO (3085 3535);
DISPLAY INVISIBLE (3085 3535);
FORCEPROP 1 LASTPIN (3075 3525) BN 8
J 0
(3063 3533);
DISPLAY 0.680851 (3063 3533);
PAINT GREEN (3063 3533);
FORCEPROP 2 LAST CDS_LIB standard
J 0
(3125 3525);
PAINT MONO (3125 3525);
DISPLAY INVISIBLE (3125 3525);
FORCEPROP 1 LAST BODY_TYPE PLUMBING
J 0
(3125 3575);
DISPLAY 0.872340 (3125 3575);
PAINT GREEN (3125 3575);
DISPLAY INVISIBLE (3125 3575);
FORCEPROP 1 LAST HDL_TAP TRUE
J 0
(3450 3400);
DISPLAY 0.872340 (3450 3400);
DISPLAY INVISIBLE (3450 3400);
FORCEPROP 1 LAST PATH I492
J 0
(3123 3525);
DISPLAY 0.872340 (3123 3525);
PAINT GREEN (3123 3525);
DISPLAY INVISIBLE (3123 3525);
FORCEADD TAP..1
(3125 3425);
FORCEPROP 3 LASTPIN (3075 3425) SIG_NAME P5E_CPU0_PE0_TX_DP<6>
J 0
(3085 3435);
DISPLAY 0.659574 (3085 3435);
PAINT MONO (3085 3435);
DISPLAY INVISIBLE (3085 3435);
FORCEPROP 1 LASTPIN (3075 3425) BN 6
J 0
(3063 3433);
DISPLAY 0.680851 (3063 3433);
PAINT GREEN (3063 3433);
FORCEPROP 2 LAST CDS_LIB standard
J 0
(3125 3425);
PAINT MONO (3125 3425);
DISPLAY INVISIBLE (3125 3425);
FORCEPROP 1 LAST BODY_TYPE PLUMBING
J 0
(3125 3475);
DISPLAY 0.872340 (3125 3475);
PAINT GREEN (3125 3475);
DISPLAY INVISIBLE (3125 3475);
FORCEPROP 1 LAST HDL_TAP TRUE
J 0
(3450 3300);
DISPLAY 0.872340 (3450 3300);
DISPLAY INVISIBLE (3450 3300);
FORCEPROP 1 LAST PATH I493
J 0
(3123 3425);
DISPLAY 0.872340 (3123 3425);
PAINT GREEN (3123 3425);
DISPLAY INVISIBLE (3123 3425);
FORCEADD TAP..1
(3125 3475);
FORCEPROP 3 LASTPIN (3075 3475) SIG_NAME P5E_CPU0_PE0_TX_DP<7>
J 0
(3085 3485);
DISPLAY 0.659574 (3085 3485);
PAINT MONO (3085 3485);
DISPLAY INVISIBLE (3085 3485);
FORCEPROP 1 LASTPIN (3075 3475) BN 7
J 0
(3063 3483);
DISPLAY 0.680851 (3063 3483);
PAINT GREEN (3063 3483);
FORCEPROP 2 LAST CDS_LIB standard
J 0
(3125 3475);
PAINT MONO (3125 3475);
DISPLAY INVISIBLE (3125 3475);
FORCEPROP 1 LAST BODY_TYPE PLUMBING
J 0
(3125 3525);
DISPLAY 0.872340 (3125 3525);
PAINT GREEN (3125 3525);
DISPLAY INVISIBLE (3125 3525);
FORCEPROP 1 LAST HDL_TAP TRUE
J 0
(3450 3350);
DISPLAY 0.872340 (3450 3350);
DISPLAY INVISIBLE (3450 3350);
FORCEPROP 1 LAST PATH I494
J 0
(3123 3475);
DISPLAY 0.872340 (3123 3475);
PAINT GREEN (3123 3475);
DISPLAY INVISIBLE (3123 3475);
FORCEADD TAP..1
(3125 3625);
FORCEPROP 3 LASTPIN (3075 3625) SIG_NAME P5E_CPU0_PE0_TX_DP<10>
J 0
(3085 3635);
DISPLAY 0.659574 (3085 3635);
PAINT MONO (3085 3635);
DISPLAY INVISIBLE (3085 3635);
FORCEPROP 1 LASTPIN (3075 3625) BN 10
J 0
(3063 3633);
DISPLAY 0.680851 (3063 3633);
PAINT GREEN (3063 3633);
FORCEPROP 2 LAST CDS_LIB standard
J 0
(3125 3625);
DISPLAY INVISIBLE (3125 3625);
FORCEPROP 1 LAST BODY_TYPE PLUMBING
J 0
(3125 3675);
DISPLAY 0.872340 (3125 3675);
PAINT GREEN (3125 3675);
DISPLAY INVISIBLE (3125 3675);
FORCEPROP 1 LAST HDL_TAP TRUE
J 0
(3450 3500);
DISPLAY 0.872340 (3450 3500);
DISPLAY INVISIBLE (3450 3500);
FORCEPROP 1 LAST PATH I495
J 0
(3123 3625);
DISPLAY 0.872340 (3123 3625);
PAINT GREEN (3123 3625);
DISPLAY INVISIBLE (3123 3625);
FORCEADD TAP..1
(3125 3575);
FORCEPROP 3 LASTPIN (3075 3575) SIG_NAME P5E_CPU0_PE0_TX_DP<9>
J 0
(3085 3585);
DISPLAY 0.659574 (3085 3585);
PAINT MONO (3085 3585);
DISPLAY INVISIBLE (3085 3585);
FORCEPROP 1 LASTPIN (3075 3575) BN 9
J 0
(3063 3583);
DISPLAY 0.680851 (3063 3583);
PAINT GREEN (3063 3583);
FORCEPROP 2 LAST CDS_LIB standard
J 0
(3125 3575);
DISPLAY INVISIBLE (3125 3575);
FORCEPROP 1 LAST BODY_TYPE PLUMBING
J 0
(3125 3625);
DISPLAY 0.872340 (3125 3625);
PAINT GREEN (3125 3625);
DISPLAY INVISIBLE (3125 3625);
FORCEPROP 1 LAST HDL_TAP TRUE
J 0
(3450 3450);
DISPLAY 0.872340 (3450 3450);
DISPLAY INVISIBLE (3450 3450);
FORCEPROP 1 LAST PATH I496
J 0
(3123 3575);
DISPLAY 0.872340 (3123 3575);
PAINT GREEN (3123 3575);
DISPLAY INVISIBLE (3123 3575);
FORCEADD TAP..1
(3125 3775);
FORCEPROP 3 LASTPIN (3075 3775) SIG_NAME P5E_CPU0_PE0_TX_DP<13>
J 0
(3085 3785);
DISPLAY 0.659574 (3085 3785);
PAINT MONO (3085 3785);
DISPLAY INVISIBLE (3085 3785);
FORCEPROP 1 LASTPIN (3075 3775) BN 13
J 0
(3063 3783);
DISPLAY 0.680851 (3063 3783);
PAINT GREEN (3063 3783);
FORCEPROP 2 LAST CDS_LIB standard
J 0
(3125 3775);
DISPLAY INVISIBLE (3125 3775);
FORCEPROP 1 LAST BODY_TYPE PLUMBING
J 0
(3125 3825);
DISPLAY 0.872340 (3125 3825);
PAINT GREEN (3125 3825);
DISPLAY INVISIBLE (3125 3825);
FORCEPROP 1 LAST HDL_TAP TRUE
J 0
(3450 3650);
DISPLAY 0.872340 (3450 3650);
DISPLAY INVISIBLE (3450 3650);
FORCEPROP 1 LAST PATH I497
J 0
(3123 3775);
DISPLAY 0.872340 (3123 3775);
PAINT GREEN (3123 3775);
DISPLAY INVISIBLE (3123 3775);
FORCEADD TAP..1
(3125 3725);
FORCEPROP 3 LASTPIN (3075 3725) SIG_NAME P5E_CPU0_PE0_TX_DP<12>
J 0
(3085 3735);
DISPLAY 0.659574 (3085 3735);
PAINT MONO (3085 3735);
DISPLAY INVISIBLE (3085 3735);
FORCEPROP 1 LASTPIN (3075 3725) BN 12
J 0
(3063 3733);
DISPLAY 0.680851 (3063 3733);
PAINT GREEN (3063 3733);
FORCEPROP 2 LAST CDS_LIB standard
J 0
(3125 3725);
DISPLAY INVISIBLE (3125 3725);
FORCEPROP 1 LAST BODY_TYPE PLUMBING
J 0
(3125 3775);
DISPLAY 0.872340 (3125 3775);
PAINT GREEN (3125 3775);
DISPLAY INVISIBLE (3125 3775);
FORCEPROP 1 LAST HDL_TAP TRUE
J 0
(3450 3600);
DISPLAY 0.872340 (3450 3600);
DISPLAY INVISIBLE (3450 3600);
FORCEPROP 1 LAST PATH I498
J 0
(3123 3725);
DISPLAY 0.872340 (3123 3725);
PAINT GREEN (3123 3725);
DISPLAY INVISIBLE (3123 3725);
FORCEADD TAP..1
(3125 3675);
FORCEPROP 3 LASTPIN (3075 3675) SIG_NAME P5E_CPU0_PE0_TX_DP<11>
J 0
(3085 3685);
DISPLAY 0.659574 (3085 3685);
PAINT MONO (3085 3685);
DISPLAY INVISIBLE (3085 3685);
FORCEPROP 1 LASTPIN (3075 3675) BN 11
J 0
(3063 3683);
DISPLAY 0.680851 (3063 3683);
PAINT GREEN (3063 3683);
FORCEPROP 2 LAST CDS_LIB standard
J 0
(3125 3675);
DISPLAY INVISIBLE (3125 3675);
FORCEPROP 1 LAST BODY_TYPE PLUMBING
J 0
(3125 3725);
DISPLAY 0.872340 (3125 3725);
PAINT GREEN (3125 3725);
DISPLAY INVISIBLE (3125 3725);
FORCEPROP 1 LAST HDL_TAP TRUE
J 0
(3450 3550);
DISPLAY 0.872340 (3450 3550);
DISPLAY INVISIBLE (3450 3550);
FORCEPROP 1 LAST PATH I499
J 0
(3123 3675);
DISPLAY 0.872340 (3123 3675);
PAINT GREEN (3123 3675);
DISPLAY INVISIBLE (3123 3675);
FORCEADD TAP..1
(3125 3875);
FORCEPROP 3 LASTPIN (3075 3875) SIG_NAME P5E_CPU0_PE0_TX_DP<15>
J 0
(3085 3885);
DISPLAY 0.659574 (3085 3885);
PAINT MONO (3085 3885);
DISPLAY INVISIBLE (3085 3885);
FORCEPROP 1 LASTPIN (3075 3875) BN 15
J 0
(3063 3883);
DISPLAY 0.680851 (3063 3883);
PAINT GREEN (3063 3883);
FORCEPROP 2 LAST CDS_LIB standard
J 0
(3125 3875);
DISPLAY INVISIBLE (3125 3875);
FORCEPROP 1 LAST BODY_TYPE PLUMBING
J 0
(3125 3925);
DISPLAY 0.872340 (3125 3925);
PAINT GREEN (3125 3925);
DISPLAY INVISIBLE (3125 3925);
FORCEPROP 1 LAST HDL_TAP TRUE
J 0
(3450 3750);
DISPLAY 0.872340 (3450 3750);
DISPLAY INVISIBLE (3450 3750);
FORCEPROP 1 LAST PATH I500
J 0
(3123 3875);
DISPLAY 0.872340 (3123 3875);
PAINT GREEN (3123 3875);
DISPLAY INVISIBLE (3123 3875);
FORCEADD TAP..1
(3125 3825);
FORCEPROP 3 LASTPIN (3075 3825) SIG_NAME P5E_CPU0_PE0_TX_DP<14>
J 0
(3085 3835);
DISPLAY 0.659574 (3085 3835);
PAINT MONO (3085 3835);
DISPLAY INVISIBLE (3085 3835);
FORCEPROP 1 LASTPIN (3075 3825) BN 14
J 0
(3063 3833);
DISPLAY 0.680851 (3063 3833);
PAINT GREEN (3063 3833);
FORCEPROP 2 LAST CDS_LIB standard
J 0
(3125 3825);
DISPLAY INVISIBLE (3125 3825);
FORCEPROP 1 LAST BODY_TYPE PLUMBING
J 0
(3125 3875);
DISPLAY 0.872340 (3125 3875);
PAINT GREEN (3125 3875);
DISPLAY INVISIBLE (3125 3875);
FORCEPROP 1 LAST HDL_TAP TRUE
J 0
(3450 3700);
DISPLAY 0.872340 (3450 3700);
DISPLAY INVISIBLE (3450 3700);
FORCEPROP 1 LAST PATH I501
J 0
(3123 3825);
DISPLAY 0.872340 (3123 3825);
PAINT GREEN (3123 3825);
DISPLAY INVISIBLE (3123 3825);
FORCEADD OFFPAGE..2
(4225 3050);
FORCEPROP 2 LAST $XR0 173 
J 0
(4414 3050);
DISPLAY 0.638298 (4414 3050);
PAINT MONO (4414 3050);
FORCEPROP 2 LAST CDS_LIB standard
J 0
(4225 3050);
PAINT MONO (4225 3050);
DISPLAY INVISIBLE (4225 3050);
FORCEPROP 1 LAST OFFPAGE TRUE
J 0
(4550 2925);
DISPLAY 1.170213 (4550 2925);
PAINT GREEN (4550 2925);
DISPLAY INVISIBLE (4550 2925);
FORCEPROP 1 LAST COMMENT_BODY TRUE
J 0
(4180 2955);
DISPLAY 1.170213 (4180 2955);
PAINT GREEN (4180 2955);
DISPLAY INVISIBLE (4180 2955);
FORCEPROP 2 LAST PATH I502
J 0
(4425 3100);
DISPLAY 1.021277 (4425 3100);
DISPLAY INVISIBLE (4425 3100);
FORCEADD OFFPAGE..2
(4225 3900);
FORCEPROP 2 LAST $XR0 173 
J 0
(4414 3900);
DISPLAY 0.638298 (4414 3900);
PAINT MONO (4414 3900);
FORCEPROP 2 LAST CDS_LIB standard
J 0
(4225 3900);
PAINT MONO (4225 3900);
DISPLAY INVISIBLE (4225 3900);
FORCEPROP 1 LAST OFFPAGE TRUE
J 0
(4550 3775);
DISPLAY 1.170213 (4550 3775);
PAINT GREEN (4550 3775);
DISPLAY INVISIBLE (4550 3775);
FORCEPROP 1 LAST COMMENT_BODY TRUE
J 0
(4180 3805);
DISPLAY 1.170213 (4180 3805);
PAINT GREEN (4180 3805);
DISPLAY INVISIBLE (4180 3805);
FORCEPROP 2 LAST PATH I503
J 0
(4425 3950);
DISPLAY 1.021277 (4425 3950);
DISPLAY INVISIBLE (4425 3950);
FORCEADD TAP..1
(3125 -375);
FORCEPROP 3 LASTPIN (3075 -375) SIG_NAME P5E_CPU0_PE1_TX_DN<2>
J 0
(3085 -365);
DISPLAY 0.659574 (3085 -365);
PAINT MONO (3085 -365);
DISPLAY INVISIBLE (3085 -365);
FORCEPROP 1 LASTPIN (3075 -375) BN 2
J 0
(3063 -367);
DISPLAY 0.680851 (3063 -367);
PAINT GREEN (3063 -367);
FORCEPROP 2 LAST CDS_LIB standard
J 0
(3125 -375);
PAINT MONO (3125 -375);
DISPLAY INVISIBLE (3125 -375);
FORCEPROP 1 LAST BODY_TYPE PLUMBING
J 0
(3125 -325);
DISPLAY 0.872340 (3125 -325);
PAINT GREEN (3125 -325);
DISPLAY INVISIBLE (3125 -325);
FORCEPROP 1 LAST HDL_TAP TRUE
J 0
(3450 -500);
DISPLAY 0.872340 (3450 -500);
DISPLAY INVISIBLE (3450 -500);
FORCEPROP 1 LAST PATH I504
J 0
(3123 -375);
DISPLAY 0.872340 (3123 -375);
PAINT GREEN (3123 -375);
DISPLAY INVISIBLE (3123 -375);
FORCEADD TAP..1
(3125 -425);
FORCEPROP 3 LASTPIN (3075 -425) SIG_NAME P5E_CPU0_PE1_TX_DN<1>
J 0
(3085 -415);
DISPLAY 0.659574 (3085 -415);
PAINT MONO (3085 -415);
DISPLAY INVISIBLE (3085 -415);
FORCEPROP 1 LASTPIN (3075 -425) BN 1
J 0
(3063 -417);
DISPLAY 0.680851 (3063 -417);
PAINT GREEN (3063 -417);
FORCEPROP 2 LAST CDS_LIB standard
J 0
(3125 -425);
PAINT MONO (3125 -425);
DISPLAY INVISIBLE (3125 -425);
FORCEPROP 1 LAST BODY_TYPE PLUMBING
J 0
(3125 -375);
DISPLAY 0.872340 (3125 -375);
PAINT GREEN (3125 -375);
DISPLAY INVISIBLE (3125 -375);
FORCEPROP 1 LAST HDL_TAP TRUE
J 0
(3450 -550);
DISPLAY 0.872340 (3450 -550);
DISPLAY INVISIBLE (3450 -550);
FORCEPROP 1 LAST PATH I505
J 0
(3123 -425);
DISPLAY 0.872340 (3123 -425);
PAINT GREEN (3123 -425);
DISPLAY INVISIBLE (3123 -425);
FORCEADD TAP..1
(3125 -475);
FORCEPROP 3 LASTPIN (3075 -475) SIG_NAME P5E_CPU0_PE1_TX_DN<0>
J 0
(3085 -465);
DISPLAY 0.659574 (3085 -465);
PAINT MONO (3085 -465);
DISPLAY INVISIBLE (3085 -465);
FORCEPROP 1 LASTPIN (3075 -475) BN 0
J 0
(3063 -467);
DISPLAY 0.680851 (3063 -467);
PAINT GREEN (3063 -467);
FORCEPROP 2 LAST CDS_LIB standard
J 0
(3125 -475);
PAINT MONO (3125 -475);
DISPLAY INVISIBLE (3125 -475);
FORCEPROP 1 LAST BODY_TYPE PLUMBING
J 0
(3125 -425);
DISPLAY 0.872340 (3125 -425);
PAINT GREEN (3125 -425);
DISPLAY INVISIBLE (3125 -425);
FORCEPROP 1 LAST HDL_TAP TRUE
J 0
(3450 -600);
DISPLAY 0.872340 (3450 -600);
DISPLAY INVISIBLE (3450 -600);
FORCEPROP 1 LAST PATH I506
J 0
(3123 -475);
DISPLAY 0.872340 (3123 -475);
PAINT GREEN (3123 -475);
DISPLAY INVISIBLE (3123 -475);
FORCEADD TAP..1
(3125 -275);
FORCEPROP 3 LASTPIN (3075 -275) SIG_NAME P5E_CPU0_PE1_TX_DN<4>
J 0
(3085 -265);
DISPLAY 0.659574 (3085 -265);
PAINT MONO (3085 -265);
DISPLAY INVISIBLE (3085 -265);
FORCEPROP 1 LASTPIN (3075 -275) BN 4
J 0
(3063 -267);
DISPLAY 0.680851 (3063 -267);
PAINT GREEN (3063 -267);
FORCEPROP 2 LAST CDS_LIB standard
J 0
(3125 -275);
PAINT MONO (3125 -275);
DISPLAY INVISIBLE (3125 -275);
FORCEPROP 1 LAST BODY_TYPE PLUMBING
J 0
(3125 -225);
DISPLAY 0.872340 (3125 -225);
PAINT GREEN (3125 -225);
DISPLAY INVISIBLE (3125 -225);
FORCEPROP 1 LAST HDL_TAP TRUE
J 0
(3450 -400);
DISPLAY 0.872340 (3450 -400);
DISPLAY INVISIBLE (3450 -400);
FORCEPROP 1 LAST PATH I507
J 0
(3123 -275);
DISPLAY 0.872340 (3123 -275);
PAINT GREEN (3123 -275);
DISPLAY INVISIBLE (3123 -275);
FORCEADD TAP..1
(3125 -325);
FORCEPROP 3 LASTPIN (3075 -325) SIG_NAME P5E_CPU0_PE1_TX_DN<3>
J 0
(3085 -315);
DISPLAY 0.659574 (3085 -315);
PAINT MONO (3085 -315);
DISPLAY INVISIBLE (3085 -315);
FORCEPROP 1 LASTPIN (3075 -325) BN 3
J 0
(3063 -317);
DISPLAY 0.680851 (3063 -317);
PAINT GREEN (3063 -317);
FORCEPROP 2 LAST CDS_LIB standard
J 0
(3125 -325);
PAINT MONO (3125 -325);
DISPLAY INVISIBLE (3125 -325);
FORCEPROP 1 LAST BODY_TYPE PLUMBING
J 0
(3125 -275);
DISPLAY 0.872340 (3125 -275);
PAINT GREEN (3125 -275);
DISPLAY INVISIBLE (3125 -275);
FORCEPROP 1 LAST HDL_TAP TRUE
J 0
(3450 -450);
DISPLAY 0.872340 (3450 -450);
DISPLAY INVISIBLE (3450 -450);
FORCEPROP 1 LAST PATH I508
J 0
(3123 -325);
DISPLAY 0.872340 (3123 -325);
PAINT GREEN (3123 -325);
DISPLAY INVISIBLE (3123 -325);
FORCEADD TAP..1
(3125 -125);
FORCEPROP 3 LASTPIN (3075 -125) SIG_NAME P5E_CPU0_PE1_TX_DN<7>
J 0
(3085 -115);
DISPLAY 0.659574 (3085 -115);
PAINT MONO (3085 -115);
DISPLAY INVISIBLE (3085 -115);
FORCEPROP 1 LASTPIN (3075 -125) BN 7
J 0
(3063 -117);
DISPLAY 0.680851 (3063 -117);
PAINT GREEN (3063 -117);
FORCEPROP 2 LAST CDS_LIB standard
J 0
(3125 -125);
PAINT MONO (3125 -125);
DISPLAY INVISIBLE (3125 -125);
FORCEPROP 1 LAST BODY_TYPE PLUMBING
J 0
(3125 -75);
DISPLAY 0.872340 (3125 -75);
PAINT GREEN (3125 -75);
DISPLAY INVISIBLE (3125 -75);
FORCEPROP 1 LAST HDL_TAP TRUE
J 0
(3450 -250);
DISPLAY 0.872340 (3450 -250);
DISPLAY INVISIBLE (3450 -250);
FORCEPROP 1 LAST PATH I509
J 0
(3123 -125);
DISPLAY 0.872340 (3123 -125);
PAINT GREEN (3123 -125);
DISPLAY INVISIBLE (3123 -125);
FORCEADD TAP..1
(3125 -175);
FORCEPROP 3 LASTPIN (3075 -175) SIG_NAME P5E_CPU0_PE1_TX_DN<6>
J 0
(3085 -165);
DISPLAY 0.659574 (3085 -165);
PAINT MONO (3085 -165);
DISPLAY INVISIBLE (3085 -165);
FORCEPROP 1 LASTPIN (3075 -175) BN 6
J 0
(3063 -167);
DISPLAY 0.680851 (3063 -167);
PAINT GREEN (3063 -167);
FORCEPROP 2 LAST CDS_LIB standard
J 0
(3125 -175);
PAINT MONO (3125 -175);
DISPLAY INVISIBLE (3125 -175);
FORCEPROP 1 LAST BODY_TYPE PLUMBING
J 0
(3125 -125);
DISPLAY 0.872340 (3125 -125);
PAINT GREEN (3125 -125);
DISPLAY INVISIBLE (3125 -125);
FORCEPROP 1 LAST HDL_TAP TRUE
J 0
(3450 -300);
DISPLAY 0.872340 (3450 -300);
DISPLAY INVISIBLE (3450 -300);
FORCEPROP 1 LAST PATH I510
J 0
(3123 -175);
DISPLAY 0.872340 (3123 -175);
PAINT GREEN (3123 -175);
DISPLAY INVISIBLE (3123 -175);
FORCEADD TAP..1
(3125 -225);
FORCEPROP 3 LASTPIN (3075 -225) SIG_NAME P5E_CPU0_PE1_TX_DN<5>
J 0
(3085 -215);
DISPLAY 0.659574 (3085 -215);
PAINT MONO (3085 -215);
DISPLAY INVISIBLE (3085 -215);
FORCEPROP 1 LASTPIN (3075 -225) BN 5
J 0
(3063 -217);
DISPLAY 0.680851 (3063 -217);
PAINT GREEN (3063 -217);
FORCEPROP 2 LAST CDS_LIB standard
J 0
(3125 -225);
PAINT MONO (3125 -225);
DISPLAY INVISIBLE (3125 -225);
FORCEPROP 1 LAST BODY_TYPE PLUMBING
J 0
(3125 -175);
DISPLAY 0.872340 (3125 -175);
PAINT GREEN (3125 -175);
DISPLAY INVISIBLE (3125 -175);
FORCEPROP 1 LAST HDL_TAP TRUE
J 0
(3450 -350);
DISPLAY 0.872340 (3450 -350);
DISPLAY INVISIBLE (3450 -350);
FORCEPROP 1 LAST PATH I511
J 0
(3123 -225);
DISPLAY 0.872340 (3123 -225);
PAINT GREEN (3123 -225);
DISPLAY INVISIBLE (3123 -225);
FORCEADD TAP..1
(3125 -75);
FORCEPROP 3 LASTPIN (3075 -75) SIG_NAME P5E_CPU0_PE1_TX_DN<8>
J 0
(3085 -65);
DISPLAY 0.659574 (3085 -65);
PAINT MONO (3085 -65);
DISPLAY INVISIBLE (3085 -65);
FORCEPROP 1 LASTPIN (3075 -75) BN 8
J 0
(3063 -67);
DISPLAY 0.680851 (3063 -67);
PAINT GREEN (3063 -67);
FORCEPROP 2 LAST CDS_LIB standard
J 0
(3125 -75);
PAINT MONO (3125 -75);
DISPLAY INVISIBLE (3125 -75);
FORCEPROP 1 LAST BODY_TYPE PLUMBING
J 0
(3125 -25);
DISPLAY 0.872340 (3125 -25);
PAINT GREEN (3125 -25);
DISPLAY INVISIBLE (3125 -25);
FORCEPROP 1 LAST HDL_TAP TRUE
J 0
(3450 -200);
DISPLAY 0.872340 (3450 -200);
DISPLAY INVISIBLE (3450 -200);
FORCEPROP 1 LAST PATH I512
J 0
(3123 -75);
DISPLAY 0.872340 (3123 -75);
PAINT GREEN (3123 -75);
DISPLAY INVISIBLE (3123 -75);
FORCEADD TAP..1
(3125 -25);
FORCEPROP 3 LASTPIN (3075 -25) SIG_NAME P5E_CPU0_PE1_TX_DN<9>
J 0
(3085 -15);
DISPLAY 0.659574 (3085 -15);
PAINT MONO (3085 -15);
DISPLAY INVISIBLE (3085 -15);
FORCEPROP 1 LASTPIN (3075 -25) BN 9
J 0
(3063 -17);
DISPLAY 0.680851 (3063 -17);
PAINT GREEN (3063 -17);
FORCEPROP 2 LAST CDS_LIB standard
J 0
(3125 -25);
DISPLAY INVISIBLE (3125 -25);
FORCEPROP 1 LAST BODY_TYPE PLUMBING
J 0
(3125 25);
DISPLAY 0.872340 (3125 25);
PAINT GREEN (3125 25);
DISPLAY INVISIBLE (3125 25);
FORCEPROP 1 LAST HDL_TAP TRUE
J 0
(3450 -150);
DISPLAY 0.872340 (3450 -150);
DISPLAY INVISIBLE (3450 -150);
FORCEPROP 1 LAST PATH I513
J 0
(3123 -25);
DISPLAY 0.872340 (3123 -25);
PAINT GREEN (3123 -25);
DISPLAY INVISIBLE (3123 -25);
FORCEADD TAP..1
(3125 125);
FORCEPROP 3 LASTPIN (3075 125) SIG_NAME P5E_CPU0_PE1_TX_DN<12>
J 0
(3085 135);
DISPLAY 0.659574 (3085 135);
PAINT MONO (3085 135);
DISPLAY INVISIBLE (3085 135);
FORCEPROP 1 LASTPIN (3075 125) BN 12
J 0
(3063 133);
DISPLAY 0.680851 (3063 133);
PAINT GREEN (3063 133);
FORCEPROP 2 LAST CDS_LIB standard
J 0
(3125 125);
DISPLAY INVISIBLE (3125 125);
FORCEPROP 1 LAST BODY_TYPE PLUMBING
J 0
(3125 175);
DISPLAY 0.872340 (3125 175);
PAINT GREEN (3125 175);
DISPLAY INVISIBLE (3125 175);
FORCEPROP 1 LAST HDL_TAP TRUE
J 0
(3450 0);
DISPLAY 0.872340 (3450 0);
DISPLAY INVISIBLE (3450 0);
FORCEPROP 1 LAST PATH I514
J 0
(3123 125);
DISPLAY 0.872340 (3123 125);
PAINT GREEN (3123 125);
DISPLAY INVISIBLE (3123 125);
FORCEADD TAP..1
(3125 25);
FORCEPROP 3 LASTPIN (3075 25) SIG_NAME P5E_CPU0_PE1_TX_DN<10>
J 0
(3085 35);
DISPLAY 0.659574 (3085 35);
PAINT MONO (3085 35);
DISPLAY INVISIBLE (3085 35);
FORCEPROP 1 LASTPIN (3075 25) BN 10
J 0
(3063 33);
DISPLAY 0.680851 (3063 33);
PAINT GREEN (3063 33);
FORCEPROP 2 LAST CDS_LIB standard
J 0
(3125 25);
DISPLAY INVISIBLE (3125 25);
FORCEPROP 1 LAST BODY_TYPE PLUMBING
J 0
(3125 75);
DISPLAY 0.872340 (3125 75);
PAINT GREEN (3125 75);
DISPLAY INVISIBLE (3125 75);
FORCEPROP 1 LAST HDL_TAP TRUE
J 0
(3450 -100);
DISPLAY 0.872340 (3450 -100);
DISPLAY INVISIBLE (3450 -100);
FORCEPROP 1 LAST PATH I515
J 0
(3123 25);
DISPLAY 0.872340 (3123 25);
PAINT GREEN (3123 25);
DISPLAY INVISIBLE (3123 25);
FORCEADD TAP..1
(3125 75);
FORCEPROP 3 LASTPIN (3075 75) SIG_NAME P5E_CPU0_PE1_TX_DN<11>
J 0
(3085 85);
DISPLAY 0.659574 (3085 85);
PAINT MONO (3085 85);
DISPLAY INVISIBLE (3085 85);
FORCEPROP 1 LASTPIN (3075 75) BN 11
J 0
(3063 83);
DISPLAY 0.680851 (3063 83);
PAINT GREEN (3063 83);
FORCEPROP 2 LAST CDS_LIB standard
J 0
(3125 75);
DISPLAY INVISIBLE (3125 75);
FORCEPROP 1 LAST BODY_TYPE PLUMBING
J 0
(3125 125);
DISPLAY 0.872340 (3125 125);
PAINT GREEN (3125 125);
DISPLAY INVISIBLE (3125 125);
FORCEPROP 1 LAST HDL_TAP TRUE
J 0
(3450 -50);
DISPLAY 0.872340 (3450 -50);
DISPLAY INVISIBLE (3450 -50);
FORCEPROP 1 LAST PATH I516
J 0
(3123 75);
DISPLAY 0.872340 (3123 75);
PAINT GREEN (3123 75);
DISPLAY INVISIBLE (3123 75);
FORCEADD TAP..1
(3125 175);
FORCEPROP 3 LASTPIN (3075 175) SIG_NAME P5E_CPU0_PE1_TX_DN<13>
J 0
(3085 185);
DISPLAY 0.659574 (3085 185);
PAINT MONO (3085 185);
DISPLAY INVISIBLE (3085 185);
FORCEPROP 1 LASTPIN (3075 175) BN 13
J 0
(3063 183);
DISPLAY 0.680851 (3063 183);
PAINT GREEN (3063 183);
FORCEPROP 2 LAST CDS_LIB standard
J 0
(3125 175);
DISPLAY INVISIBLE (3125 175);
FORCEPROP 1 LAST BODY_TYPE PLUMBING
J 0
(3125 225);
DISPLAY 0.872340 (3125 225);
PAINT GREEN (3125 225);
DISPLAY INVISIBLE (3125 225);
FORCEPROP 1 LAST HDL_TAP TRUE
J 0
(3450 50);
DISPLAY 0.872340 (3450 50);
DISPLAY INVISIBLE (3450 50);
FORCEPROP 1 LAST PATH I517
J 0
(3123 175);
DISPLAY 0.872340 (3123 175);
PAINT GREEN (3123 175);
DISPLAY INVISIBLE (3123 175);
FORCEADD TAP..1
(3125 225);
FORCEPROP 3 LASTPIN (3075 225) SIG_NAME P5E_CPU0_PE1_TX_DN<14>
J 0
(3085 235);
DISPLAY 0.659574 (3085 235);
PAINT MONO (3085 235);
DISPLAY INVISIBLE (3085 235);
FORCEPROP 1 LASTPIN (3075 225) BN 14
J 0
(3063 233);
DISPLAY 0.680851 (3063 233);
PAINT GREEN (3063 233);
FORCEPROP 2 LAST CDS_LIB standard
J 0
(3125 225);
DISPLAY INVISIBLE (3125 225);
FORCEPROP 1 LAST BODY_TYPE PLUMBING
J 0
(3125 275);
DISPLAY 0.872340 (3125 275);
PAINT GREEN (3125 275);
DISPLAY INVISIBLE (3125 275);
FORCEPROP 1 LAST HDL_TAP TRUE
J 0
(3450 100);
DISPLAY 0.872340 (3450 100);
DISPLAY INVISIBLE (3450 100);
FORCEPROP 1 LAST PATH I518
J 0
(3123 225);
DISPLAY 0.872340 (3123 225);
PAINT GREEN (3123 225);
DISPLAY INVISIBLE (3123 225);
FORCEADD TAP..1
(3125 275);
FORCEPROP 3 LASTPIN (3075 275) SIG_NAME P5E_CPU0_PE1_TX_DN<15>
J 0
(3085 285);
DISPLAY 0.659574 (3085 285);
PAINT MONO (3085 285);
DISPLAY INVISIBLE (3085 285);
FORCEPROP 1 LASTPIN (3075 275) BN 15
J 0
(3063 283);
DISPLAY 0.680851 (3063 283);
PAINT GREEN (3063 283);
FORCEPROP 2 LAST CDS_LIB standard
J 0
(3125 275);
DISPLAY INVISIBLE (3125 275);
FORCEPROP 1 LAST BODY_TYPE PLUMBING
J 0
(3125 325);
DISPLAY 0.872340 (3125 325);
PAINT GREEN (3125 325);
DISPLAY INVISIBLE (3125 325);
FORCEPROP 1 LAST HDL_TAP TRUE
J 0
(3450 150);
DISPLAY 0.872340 (3450 150);
DISPLAY INVISIBLE (3450 150);
FORCEPROP 1 LAST PATH I519
J 0
(3123 275);
DISPLAY 0.872340 (3123 275);
PAINT GREEN (3123 275);
DISPLAY INVISIBLE (3123 275);
FORCEADD TAP..1
(3125 375);
FORCEPROP 3 LASTPIN (3075 375) SIG_NAME P5E_CPU0_PE1_TX_DP<0>
J 0
(3085 385);
DISPLAY 0.659574 (3085 385);
PAINT MONO (3085 385);
DISPLAY INVISIBLE (3085 385);
FORCEPROP 1 LASTPIN (3075 375) BN 0
J 0
(3063 383);
DISPLAY 0.680851 (3063 383);
PAINT GREEN (3063 383);
FORCEPROP 2 LAST CDS_LIB standard
J 0
(3125 375);
PAINT MONO (3125 375);
DISPLAY INVISIBLE (3125 375);
FORCEPROP 1 LAST BODY_TYPE PLUMBING
J 0
(3125 425);
DISPLAY 0.872340 (3125 425);
PAINT GREEN (3125 425);
DISPLAY INVISIBLE (3125 425);
FORCEPROP 1 LAST HDL_TAP TRUE
J 0
(3450 250);
DISPLAY 0.872340 (3450 250);
DISPLAY INVISIBLE (3450 250);
FORCEPROP 1 LAST PATH I520
J 0
(3123 375);
DISPLAY 0.872340 (3123 375);
PAINT GREEN (3123 375);
DISPLAY INVISIBLE (3123 375);
FORCEADD TAP..1
(3125 525);
FORCEPROP 3 LASTPIN (3075 525) SIG_NAME P5E_CPU0_PE1_TX_DP<3>
J 0
(3085 535);
DISPLAY 0.659574 (3085 535);
PAINT MONO (3085 535);
DISPLAY INVISIBLE (3085 535);
FORCEPROP 1 LASTPIN (3075 525) BN 3
J 0
(3063 533);
DISPLAY 0.680851 (3063 533);
PAINT GREEN (3063 533);
FORCEPROP 2 LAST CDS_LIB standard
J 0
(3125 525);
PAINT MONO (3125 525);
DISPLAY INVISIBLE (3125 525);
FORCEPROP 1 LAST BODY_TYPE PLUMBING
J 0
(3125 575);
DISPLAY 0.872340 (3125 575);
PAINT GREEN (3125 575);
DISPLAY INVISIBLE (3125 575);
FORCEPROP 1 LAST HDL_TAP TRUE
J 0
(3450 400);
DISPLAY 0.872340 (3450 400);
DISPLAY INVISIBLE (3450 400);
FORCEPROP 1 LAST PATH I521
J 0
(3123 525);
DISPLAY 0.872340 (3123 525);
PAINT GREEN (3123 525);
DISPLAY INVISIBLE (3123 525);
FORCEADD TAP..1
(3125 425);
FORCEPROP 3 LASTPIN (3075 425) SIG_NAME P5E_CPU0_PE1_TX_DP<1>
J 0
(3085 435);
DISPLAY 0.659574 (3085 435);
PAINT MONO (3085 435);
DISPLAY INVISIBLE (3085 435);
FORCEPROP 1 LASTPIN (3075 425) BN 1
J 0
(3063 433);
DISPLAY 0.680851 (3063 433);
PAINT GREEN (3063 433);
FORCEPROP 2 LAST CDS_LIB standard
J 0
(3125 425);
PAINT MONO (3125 425);
DISPLAY INVISIBLE (3125 425);
FORCEPROP 1 LAST BODY_TYPE PLUMBING
J 0
(3125 475);
DISPLAY 0.872340 (3125 475);
PAINT GREEN (3125 475);
DISPLAY INVISIBLE (3125 475);
FORCEPROP 1 LAST HDL_TAP TRUE
J 0
(3450 300);
DISPLAY 0.872340 (3450 300);
DISPLAY INVISIBLE (3450 300);
FORCEPROP 1 LAST PATH I522
J 0
(3123 425);
DISPLAY 0.872340 (3123 425);
PAINT GREEN (3123 425);
DISPLAY INVISIBLE (3123 425);
FORCEADD TAP..1
(3125 475);
FORCEPROP 3 LASTPIN (3075 475) SIG_NAME P5E_CPU0_PE1_TX_DP<2>
J 0
(3085 485);
DISPLAY 0.659574 (3085 485);
PAINT MONO (3085 485);
DISPLAY INVISIBLE (3085 485);
FORCEPROP 1 LASTPIN (3075 475) BN 2
J 0
(3063 483);
DISPLAY 0.680851 (3063 483);
PAINT GREEN (3063 483);
FORCEPROP 2 LAST CDS_LIB standard
J 0
(3125 475);
PAINT MONO (3125 475);
DISPLAY INVISIBLE (3125 475);
FORCEPROP 1 LAST BODY_TYPE PLUMBING
J 0
(3125 525);
DISPLAY 0.872340 (3125 525);
PAINT GREEN (3125 525);
DISPLAY INVISIBLE (3125 525);
FORCEPROP 1 LAST HDL_TAP TRUE
J 0
(3450 350);
DISPLAY 0.872340 (3450 350);
DISPLAY INVISIBLE (3450 350);
FORCEPROP 1 LAST PATH I523
J 0
(3123 475);
DISPLAY 0.872340 (3123 475);
PAINT GREEN (3123 475);
DISPLAY INVISIBLE (3123 475);
FORCEADD TAP..1
(3125 625);
FORCEPROP 3 LASTPIN (3075 625) SIG_NAME P5E_CPU0_PE1_TX_DP<5>
J 0
(3085 635);
DISPLAY 0.659574 (3085 635);
PAINT MONO (3085 635);
DISPLAY INVISIBLE (3085 635);
FORCEPROP 1 LASTPIN (3075 625) BN 5
J 0
(3063 633);
DISPLAY 0.680851 (3063 633);
PAINT GREEN (3063 633);
FORCEPROP 2 LAST CDS_LIB standard
J 0
(3125 625);
PAINT MONO (3125 625);
DISPLAY INVISIBLE (3125 625);
FORCEPROP 1 LAST BODY_TYPE PLUMBING
J 0
(3125 675);
DISPLAY 0.872340 (3125 675);
PAINT GREEN (3125 675);
DISPLAY INVISIBLE (3125 675);
FORCEPROP 1 LAST HDL_TAP TRUE
J 0
(3450 500);
DISPLAY 0.872340 (3450 500);
DISPLAY INVISIBLE (3450 500);
FORCEPROP 1 LAST PATH I524
J 0
(3123 625);
DISPLAY 0.872340 (3123 625);
PAINT GREEN (3123 625);
DISPLAY INVISIBLE (3123 625);
FORCEADD TAP..1
(3125 575);
FORCEPROP 3 LASTPIN (3075 575) SIG_NAME P5E_CPU0_PE1_TX_DP<4>
J 0
(3085 585);
DISPLAY 0.659574 (3085 585);
PAINT MONO (3085 585);
DISPLAY INVISIBLE (3085 585);
FORCEPROP 1 LASTPIN (3075 575) BN 4
J 0
(3063 583);
DISPLAY 0.680851 (3063 583);
PAINT GREEN (3063 583);
FORCEPROP 2 LAST CDS_LIB standard
J 0
(3125 575);
PAINT MONO (3125 575);
DISPLAY INVISIBLE (3125 575);
FORCEPROP 1 LAST BODY_TYPE PLUMBING
J 0
(3125 625);
DISPLAY 0.872340 (3125 625);
PAINT GREEN (3125 625);
DISPLAY INVISIBLE (3125 625);
FORCEPROP 1 LAST HDL_TAP TRUE
J 0
(3450 450);
DISPLAY 0.872340 (3450 450);
DISPLAY INVISIBLE (3450 450);
FORCEPROP 1 LAST PATH I525
J 0
(3123 575);
DISPLAY 0.872340 (3123 575);
PAINT GREEN (3123 575);
DISPLAY INVISIBLE (3123 575);
FORCEADD TAP..1
(3125 775);
FORCEPROP 3 LASTPIN (3075 775) SIG_NAME P5E_CPU0_PE1_TX_DP<8>
J 0
(3085 785);
DISPLAY 0.659574 (3085 785);
PAINT MONO (3085 785);
DISPLAY INVISIBLE (3085 785);
FORCEPROP 1 LASTPIN (3075 775) BN 8
J 0
(3063 783);
DISPLAY 0.680851 (3063 783);
PAINT GREEN (3063 783);
FORCEPROP 2 LAST CDS_LIB standard
J 0
(3125 775);
PAINT MONO (3125 775);
DISPLAY INVISIBLE (3125 775);
FORCEPROP 1 LAST BODY_TYPE PLUMBING
J 0
(3125 825);
DISPLAY 0.872340 (3125 825);
PAINT GREEN (3125 825);
DISPLAY INVISIBLE (3125 825);
FORCEPROP 1 LAST HDL_TAP TRUE
J 0
(3450 650);
DISPLAY 0.872340 (3450 650);
DISPLAY INVISIBLE (3450 650);
FORCEPROP 1 LAST PATH I526
J 0
(3123 775);
DISPLAY 0.872340 (3123 775);
PAINT GREEN (3123 775);
DISPLAY INVISIBLE (3123 775);
FORCEADD TAP..1
(3125 675);
FORCEPROP 3 LASTPIN (3075 675) SIG_NAME P5E_CPU0_PE1_TX_DP<6>
J 0
(3085 685);
DISPLAY 0.659574 (3085 685);
PAINT MONO (3085 685);
DISPLAY INVISIBLE (3085 685);
FORCEPROP 1 LASTPIN (3075 675) BN 6
J 0
(3063 683);
DISPLAY 0.680851 (3063 683);
PAINT GREEN (3063 683);
FORCEPROP 2 LAST CDS_LIB standard
J 0
(3125 675);
PAINT MONO (3125 675);
DISPLAY INVISIBLE (3125 675);
FORCEPROP 1 LAST BODY_TYPE PLUMBING
J 0
(3125 725);
DISPLAY 0.872340 (3125 725);
PAINT GREEN (3125 725);
DISPLAY INVISIBLE (3125 725);
FORCEPROP 1 LAST HDL_TAP TRUE
J 0
(3450 550);
DISPLAY 0.872340 (3450 550);
DISPLAY INVISIBLE (3450 550);
FORCEPROP 1 LAST PATH I527
J 0
(3123 675);
DISPLAY 0.872340 (3123 675);
PAINT GREEN (3123 675);
DISPLAY INVISIBLE (3123 675);
FORCEADD TAP..1
(3125 725);
FORCEPROP 3 LASTPIN (3075 725) SIG_NAME P5E_CPU0_PE1_TX_DP<7>
J 0
(3085 735);
DISPLAY 0.659574 (3085 735);
PAINT MONO (3085 735);
DISPLAY INVISIBLE (3085 735);
FORCEPROP 1 LASTPIN (3075 725) BN 7
J 0
(3063 733);
DISPLAY 0.680851 (3063 733);
PAINT GREEN (3063 733);
FORCEPROP 2 LAST CDS_LIB standard
J 0
(3125 725);
PAINT MONO (3125 725);
DISPLAY INVISIBLE (3125 725);
FORCEPROP 1 LAST BODY_TYPE PLUMBING
J 0
(3125 775);
DISPLAY 0.872340 (3125 775);
PAINT GREEN (3125 775);
DISPLAY INVISIBLE (3125 775);
FORCEPROP 1 LAST HDL_TAP TRUE
J 0
(3450 600);
DISPLAY 0.872340 (3450 600);
DISPLAY INVISIBLE (3450 600);
FORCEPROP 1 LAST PATH I528
J 0
(3123 725);
DISPLAY 0.872340 (3123 725);
PAINT GREEN (3123 725);
DISPLAY INVISIBLE (3123 725);
FORCEADD TAP..1
(3125 875);
FORCEPROP 3 LASTPIN (3075 875) SIG_NAME P5E_CPU0_PE1_TX_DP<10>
J 0
(3085 885);
DISPLAY 0.659574 (3085 885);
PAINT MONO (3085 885);
DISPLAY INVISIBLE (3085 885);
FORCEPROP 1 LASTPIN (3075 875) BN 10
J 0
(3063 883);
DISPLAY 0.680851 (3063 883);
PAINT GREEN (3063 883);
FORCEPROP 2 LAST CDS_LIB standard
J 0
(3125 875);
DISPLAY INVISIBLE (3125 875);
FORCEPROP 1 LAST BODY_TYPE PLUMBING
J 0
(3125 925);
DISPLAY 0.872340 (3125 925);
PAINT GREEN (3125 925);
DISPLAY INVISIBLE (3125 925);
FORCEPROP 1 LAST HDL_TAP TRUE
J 0
(3450 750);
DISPLAY 0.872340 (3450 750);
DISPLAY INVISIBLE (3450 750);
FORCEPROP 1 LAST PATH I529
J 0
(3123 875);
DISPLAY 0.872340 (3123 875);
PAINT GREEN (3123 875);
DISPLAY INVISIBLE (3123 875);
FORCEADD TAP..1
(3125 825);
FORCEPROP 3 LASTPIN (3075 825) SIG_NAME P5E_CPU0_PE1_TX_DP<9>
J 0
(3085 835);
DISPLAY 0.659574 (3085 835);
PAINT MONO (3085 835);
DISPLAY INVISIBLE (3085 835);
FORCEPROP 1 LASTPIN (3075 825) BN 9
J 0
(3063 833);
DISPLAY 0.680851 (3063 833);
PAINT GREEN (3063 833);
FORCEPROP 2 LAST CDS_LIB standard
J 0
(3125 825);
DISPLAY INVISIBLE (3125 825);
FORCEPROP 1 LAST BODY_TYPE PLUMBING
J 0
(3125 875);
DISPLAY 0.872340 (3125 875);
PAINT GREEN (3125 875);
DISPLAY INVISIBLE (3125 875);
FORCEPROP 1 LAST HDL_TAP TRUE
J 0
(3450 700);
DISPLAY 0.872340 (3450 700);
DISPLAY INVISIBLE (3450 700);
FORCEPROP 1 LAST PATH I530
J 0
(3123 825);
DISPLAY 0.872340 (3123 825);
PAINT GREEN (3123 825);
DISPLAY INVISIBLE (3123 825);
FORCEADD TAP..1
(3125 1025);
FORCEPROP 3 LASTPIN (3075 1025) SIG_NAME P5E_CPU0_PE1_TX_DP<13>
J 0
(3085 1035);
DISPLAY 0.659574 (3085 1035);
PAINT MONO (3085 1035);
DISPLAY INVISIBLE (3085 1035);
FORCEPROP 1 LASTPIN (3075 1025) BN 13
J 0
(3063 1033);
DISPLAY 0.680851 (3063 1033);
PAINT GREEN (3063 1033);
FORCEPROP 2 LAST CDS_LIB standard
J 0
(3125 1025);
DISPLAY INVISIBLE (3125 1025);
FORCEPROP 1 LAST BODY_TYPE PLUMBING
J 0
(3125 1075);
DISPLAY 0.872340 (3125 1075);
PAINT GREEN (3125 1075);
DISPLAY INVISIBLE (3125 1075);
FORCEPROP 1 LAST HDL_TAP TRUE
J 0
(3450 900);
DISPLAY 0.872340 (3450 900);
DISPLAY INVISIBLE (3450 900);
FORCEPROP 1 LAST PATH I531
J 0
(3123 1025);
DISPLAY 0.872340 (3123 1025);
PAINT GREEN (3123 1025);
DISPLAY INVISIBLE (3123 1025);
FORCEADD TAP..1
(3125 975);
FORCEPROP 3 LASTPIN (3075 975) SIG_NAME P5E_CPU0_PE1_TX_DP<12>
J 0
(3085 985);
DISPLAY 0.659574 (3085 985);
PAINT MONO (3085 985);
DISPLAY INVISIBLE (3085 985);
FORCEPROP 1 LASTPIN (3075 975) BN 12
J 0
(3063 983);
DISPLAY 0.680851 (3063 983);
PAINT GREEN (3063 983);
FORCEPROP 2 LAST CDS_LIB standard
J 0
(3125 975);
DISPLAY INVISIBLE (3125 975);
FORCEPROP 1 LAST BODY_TYPE PLUMBING
J 0
(3125 1025);
DISPLAY 0.872340 (3125 1025);
PAINT GREEN (3125 1025);
DISPLAY INVISIBLE (3125 1025);
FORCEPROP 1 LAST HDL_TAP TRUE
J 0
(3450 850);
DISPLAY 0.872340 (3450 850);
DISPLAY INVISIBLE (3450 850);
FORCEPROP 1 LAST PATH I532
J 0
(3123 975);
DISPLAY 0.872340 (3123 975);
PAINT GREEN (3123 975);
DISPLAY INVISIBLE (3123 975);
FORCEADD TAP..1
(3125 925);
FORCEPROP 3 LASTPIN (3075 925) SIG_NAME P5E_CPU0_PE1_TX_DP<11>
J 0
(3085 935);
DISPLAY 0.659574 (3085 935);
PAINT MONO (3085 935);
DISPLAY INVISIBLE (3085 935);
FORCEPROP 1 LASTPIN (3075 925) BN 11
J 0
(3063 933);
DISPLAY 0.680851 (3063 933);
PAINT GREEN (3063 933);
FORCEPROP 2 LAST CDS_LIB standard
J 0
(3125 925);
DISPLAY INVISIBLE (3125 925);
FORCEPROP 1 LAST BODY_TYPE PLUMBING
J 0
(3125 975);
DISPLAY 0.872340 (3125 975);
PAINT GREEN (3125 975);
DISPLAY INVISIBLE (3125 975);
FORCEPROP 1 LAST HDL_TAP TRUE
J 0
(3450 800);
DISPLAY 0.872340 (3450 800);
DISPLAY INVISIBLE (3450 800);
FORCEPROP 1 LAST PATH I533
J 0
(3123 925);
DISPLAY 0.872340 (3123 925);
PAINT GREEN (3123 925);
DISPLAY INVISIBLE (3123 925);
FORCEADD TAP..1
(3125 1125);
FORCEPROP 3 LASTPIN (3075 1125) SIG_NAME P5E_CPU0_PE1_TX_DP<15>
J 0
(3085 1135);
DISPLAY 0.659574 (3085 1135);
PAINT MONO (3085 1135);
DISPLAY INVISIBLE (3085 1135);
FORCEPROP 1 LASTPIN (3075 1125) BN 15
J 0
(3063 1133);
DISPLAY 0.680851 (3063 1133);
PAINT GREEN (3063 1133);
FORCEPROP 2 LAST CDS_LIB standard
J 0
(3125 1125);
DISPLAY INVISIBLE (3125 1125);
FORCEPROP 1 LAST BODY_TYPE PLUMBING
J 0
(3125 1175);
DISPLAY 0.872340 (3125 1175);
PAINT GREEN (3125 1175);
DISPLAY INVISIBLE (3125 1175);
FORCEPROP 1 LAST HDL_TAP TRUE
J 0
(3450 1000);
DISPLAY 0.872340 (3450 1000);
DISPLAY INVISIBLE (3450 1000);
FORCEPROP 1 LAST PATH I534
J 0
(3123 1125);
DISPLAY 0.872340 (3123 1125);
PAINT GREEN (3123 1125);
DISPLAY INVISIBLE (3123 1125);
FORCEADD TAP..1
(3125 1075);
FORCEPROP 3 LASTPIN (3075 1075) SIG_NAME P5E_CPU0_PE1_TX_DP<14>
J 0
(3085 1085);
DISPLAY 0.659574 (3085 1085);
PAINT MONO (3085 1085);
DISPLAY INVISIBLE (3085 1085);
FORCEPROP 1 LASTPIN (3075 1075) BN 14
J 0
(3063 1083);
DISPLAY 0.680851 (3063 1083);
PAINT GREEN (3063 1083);
FORCEPROP 2 LAST CDS_LIB standard
J 0
(3125 1075);
DISPLAY INVISIBLE (3125 1075);
FORCEPROP 1 LAST BODY_TYPE PLUMBING
J 0
(3125 1125);
DISPLAY 0.872340 (3125 1125);
PAINT GREEN (3125 1125);
DISPLAY INVISIBLE (3125 1125);
FORCEPROP 1 LAST HDL_TAP TRUE
J 0
(3450 950);
DISPLAY 0.872340 (3450 950);
DISPLAY INVISIBLE (3450 950);
FORCEPROP 1 LAST PATH I535
J 0
(3123 1075);
DISPLAY 0.872340 (3123 1075);
PAINT GREEN (3123 1075);
DISPLAY INVISIBLE (3123 1075);
FORCEADD OFFPAGE..2
(4225 300);
FORCEPROP 2 LAST $XR0 174 
J 0
(4414 300);
DISPLAY 0.638298 (4414 300);
PAINT MONO (4414 300);
FORCEPROP 2 LAST CDS_LIB standard
J 0
(4225 300);
PAINT MONO (4225 300);
DISPLAY INVISIBLE (4225 300);
FORCEPROP 1 LAST OFFPAGE TRUE
J 0
(4550 175);
DISPLAY 1.170213 (4550 175);
PAINT GREEN (4550 175);
DISPLAY INVISIBLE (4550 175);
FORCEPROP 1 LAST COMMENT_BODY TRUE
J 0
(4180 205);
DISPLAY 1.170213 (4180 205);
PAINT GREEN (4180 205);
DISPLAY INVISIBLE (4180 205);
FORCEPROP 2 LAST PATH I536
J 0
(4425 350);
DISPLAY 1.021277 (4425 350);
DISPLAY INVISIBLE (4425 350);
FORCEADD OFFPAGE..2
(4225 1150);
FORCEPROP 2 LAST $XR0 174 
J 0
(4414 1150);
DISPLAY 0.638298 (4414 1150);
PAINT MONO (4414 1150);
FORCEPROP 2 LAST CDS_LIB standard
J 0
(4225 1150);
PAINT MONO (4225 1150);
DISPLAY INVISIBLE (4225 1150);
FORCEPROP 1 LAST OFFPAGE TRUE
J 0
(4550 1025);
DISPLAY 1.170213 (4550 1025);
PAINT GREEN (4550 1025);
DISPLAY INVISIBLE (4550 1025);
FORCEPROP 1 LAST COMMENT_BODY TRUE
J 0
(4180 1055);
DISPLAY 1.170213 (4180 1055);
PAINT GREEN (4180 1055);
DISPLAY INVISIBLE (4180 1055);
FORCEPROP 2 LAST PATH I537
J 0
(4425 1200);
DISPLAY 1.021277 (4425 1200);
DISPLAY INVISIBLE (4425 1200);
FORCEADD QUANTA_TITLE_BLOCK_C..1
(6000 -1600);
FORCEPROP 0 LAST CDS_CON_LAST_MODIFIED Fri Aug 25 14:00:14 2023
J 0
(4115 -1585);
PAINT MONO (4115 -1585);
DISPLAY INVISIBLE (4115 -1585);
FORCEPROP 1 LAST CUSTOM_TXT_CDS <CON_LAST_MODIFIED>
J 0
(4115 -1585);
DISPLAY 0.978723 (4115 -1585);
FORCEPROP 2 LAST CUSTOM_TXT_CDS <XR_PAGE_TITLE>
J 0
(-1890 3650);
DISPLAY 0.638298 (-1890 3650);
PAINT PINK (-1890 3650);
DISPLAY INVISIBLE (-1890 3650);
FORCEPROP 2 LAST CUSTOM_TXT_CDS <Q_NUMBER>
J 0
(4597 -1497);
DISPLAY 1.212766 (4597 -1497);
FORCEPROP 2 LAST CUSTOM_TXT_CDS 01
J 0
(5816 -1497);
DISPLAY 1.212766 (5816 -1497);
FORCEPROP 1 LAST CUSTOM_TXT_CDS <NAME_2>
J 0
(2825 -1550);
FORCEPROP 1 LAST CUSTOM_TXT_CDS <NAME_1>
J 0
(2825 -1425);
FORCEPROP 1 LAST CUSTOM_TXT_CDS <Q_PROJ>
J 0
(3618 -1498);
DISPLAY 1.212766 (3618 -1498);
FORCEPROP 1 LAST CUSTOM_TXT_CDS <Q_REV>
J 0
(5816 -1497);
DISPLAY 1.212766 (5816 -1497);
FORCEPROP 1 LAST CUSTOM_TXT_CDS <CON_PAGE_NUM> OF <CON_TOTAL_PAGES>
J 0
(5554 -1582);
DISPLAY 0.978723 (5554 -1582);
FORCEPROP 1 LAST Q_TITLE SPR CPU0 - PCIE PE0/PE1 (17 OF 30)
J 0
(-3366 -1574);
DISPLAY 1.957447 (-3366 -1574);
PAINT GREEN (-3366 -1574);
FORCEPROP 1 LAST Q_DEPT 
J 1
(2237 -1551);
DISPLAY 1.957447 (2237 -1551);
PAINT GREEN (2237 -1551);
FORCEPROP 2 LAST CDS_LIB pure_quanta
J 0
(6000 -1600);
PAINT MONO (6000 -1600);
DISPLAY INVISIBLE (6000 -1600);
FORCEPROP 1 LAST CDS_LMAN_SYM_OUTLINE -9475,6775,100,-125
J 0
(6000 -1600);
DISPLAY 0.468085 (6000 -1600);
PAINT GREEN (6000 -1600);
DISPLAY INVISIBLE (6000 -1600);
FORCEPROP 2 LAST PAGE_BORDER TRUE
J 0
(-1890 3650);
DISPLAY 0.638298 (-1890 3650);
PAINT PINK (-1890 3650);
DISPLAY INVISIBLE (-1890 3650);
FORCEPROP 2 LAST CDS_XR_PAGE_TITLE CR-29 : @S9S_MB_2U_LIB.S9S_MB_2U(SCH_1):PAGE29
J 0
(-1890 3650);
DISPLAY 0.638298 (-1890 3650);
PAINT PINK (-1890 3650);
DISPLAY INVISIBLE (-1890 3650);
FORCEPROP 1 LAST COMMENT_BODY TRUE
J 0
(6012 -1613);
DISPLAY 0.978723 (6012 -1613);
PAINT GREEN (6012 -1613);
DISPLAY INVISIBLE (6012 -1613);
WIRE 17 -1 (3175 3150)(3175 3200);
WIRE 17 -1 (3175 3200)(3175 3250);
WIRE 17 -1 (3175 3250)(3175 3300);
WIRE 17 -1 (3175 3300)(3175 3350);
WIRE 17 -1 (3175 3350)(3175 3400);
WIRE 17 -1 (3175 3400)(3175 3450);
WIRE 17 -1 (3175 3450)(3175 3500);
WIRE 17 -1 (3175 3500)(3175 3550);
WIRE 17 -1 (3175 3550)(3175 3600);
WIRE 17 -1 (3175 3600)(3175 3650);
WIRE 17 -1 (3175 3650)(3175 3700);
WIRE 17 -1 (3175 3700)(3175 3750);
WIRE 17 -1 (3175 3750)(3175 3800);
WIRE 17 -1 (3175 3800)(3175 3850);
WIRE 17 -1 (3175 3850)(3175 3900);
WIRE 17 -1 (3175 3900)(4175 3900);
FORCEPROP 2 LAST SIG_NAME P5E_CPU0_PE0_TX_DP<15:0>
J 0
(3315 3910);
DISPLAY 0.680851 (3315 3910);
PAINT WHITE (3315 3910);
WIRE 17 -1 (3175 2300)(3175 2350);
WIRE 17 -1 (3175 2350)(3175 2400);
WIRE 17 -1 (3175 2400)(3175 2450);
WIRE 17 -1 (3175 2450)(3175 2500);
WIRE 17 -1 (3175 2500)(3175 2550);
WIRE 17 -1 (3175 2550)(3175 2600);
WIRE 17 -1 (3175 2600)(3175 2650);
WIRE 17 -1 (3175 2650)(3175 2700);
WIRE 17 -1 (3175 2700)(3175 2750);
WIRE 17 -1 (3175 2750)(3175 2800);
WIRE 17 -1 (3175 2800)(3175 2850);
WIRE 17 -1 (3175 2850)(3175 2900);
WIRE 17 -1 (3175 2900)(3175 2950);
WIRE 17 -1 (3175 2950)(3175 3000);
WIRE 17 -1 (3175 3000)(3175 3050);
WIRE 17 -1 (3175 3050)(4175 3050);
FORCEPROP 2 LAST SIG_NAME P5E_CPU0_PE0_TX_DN<15:0>
J 0
(3315 3060);
DISPLAY 0.680851 (3315 3060);
PAINT WHITE (3315 3060);
WIRE 17 -1 (-325 3150)(-325 3200);
WIRE 17 -1 (-325 3200)(-325 3250);
WIRE 17 -1 (-325 3250)(-325 3300);
WIRE 17 -1 (-325 3300)(-325 3350);
WIRE 17 -1 (-325 3350)(-325 3400);
WIRE 17 -1 (-325 3400)(-325 3450);
WIRE 17 -1 (-325 3450)(-325 3500);
WIRE 17 -1 (-325 3500)(-325 3550);
WIRE 17 -1 (-325 3550)(-325 3600);
WIRE 17 -1 (-325 3600)(-325 3650);
WIRE 17 -1 (-325 3650)(-325 3700);
WIRE 17 -1 (-325 3700)(-325 3750);
WIRE 17 -1 (-325 3750)(-325 3800);
WIRE 17 -1 (-325 3800)(-325 3850);
WIRE 17 -1 (-325 3850)(-325 3900);
WIRE 17 -1 (-1475 3900)(-325 3900);
FORCEPROP 2 LAST SIG_NAME P5E_CPU0_PE0_RX_DP<15:0>
J 0
(-1360 3910);
DISPLAY 0.680851 (-1360 3910);
PAINT WHITE (-1360 3910);
WIRE 17 -1 (-325 2300)(-325 2350);
WIRE 17 -1 (-325 2350)(-325 2400);
WIRE 17 -1 (-325 2400)(-325 2450);
WIRE 17 -1 (-325 2450)(-325 2500);
WIRE 17 -1 (-325 2500)(-325 2550);
WIRE 17 -1 (-325 2550)(-325 2600);
WIRE 17 -1 (-325 2600)(-325 2650);
WIRE 17 -1 (-325 2650)(-325 2700);
WIRE 17 -1 (-325 2700)(-325 2750);
WIRE 17 -1 (-325 2750)(-325 2800);
WIRE 17 -1 (-325 2800)(-325 2850);
WIRE 17 -1 (-325 2850)(-325 2900);
WIRE 17 -1 (-325 2900)(-325 2950);
WIRE 17 -1 (-325 2950)(-325 3000);
WIRE 17 -1 (-325 3000)(-325 3050);
WIRE 17 -1 (-1475 3050)(-325 3050);
FORCEPROP 2 LAST SIG_NAME P5E_CPU0_PE0_RX_DN<15:0>
J 0
(-1360 3060);
DISPLAY 0.680851 (-1360 3060);
PAINT WHITE (-1360 3060);
WIRE 17 -1 (3175 400)(3175 450);
WIRE 17 -1 (3175 450)(3175 500);
WIRE 17 -1 (3175 500)(3175 550);
WIRE 17 -1 (3175 550)(3175 600);
WIRE 17 -1 (3175 600)(3175 650);
WIRE 17 -1 (3175 650)(3175 700);
WIRE 17 -1 (3175 700)(3175 750);
WIRE 17 -1 (3175 750)(3175 800);
WIRE 17 -1 (3175 800)(3175 850);
WIRE 17 -1 (3175 850)(3175 900);
WIRE 17 -1 (3175 900)(3175 950);
WIRE 17 -1 (3175 950)(3175 1000);
WIRE 17 -1 (3175 1000)(3175 1050);
WIRE 17 -1 (3175 1050)(3175 1100);
WIRE 17 -1 (3175 1100)(3175 1150);
WIRE 17 -1 (3175 1150)(4175 1150);
FORCEPROP 2 LAST SIG_NAME P5E_CPU0_PE1_TX_DP<15:0>
J 0
(3315 1160);
DISPLAY 0.680851 (3315 1160);
PAINT WHITE (3315 1160);
WIRE 17 -1 (3175 -450)(3175 -400);
WIRE 17 -1 (3175 -400)(3175 -350);
WIRE 17 -1 (3175 -350)(3175 -300);
WIRE 17 -1 (3175 -300)(3175 -250);
WIRE 17 -1 (3175 -250)(3175 -200);
WIRE 17 -1 (3175 -200)(3175 -150);
WIRE 17 -1 (3175 -150)(3175 -100);
WIRE 17 -1 (3175 -100)(3175 -50);
WIRE 17 -1 (3175 -50)(3175 0);
WIRE 17 -1 (3175 0)(3175 50);
WIRE 17 -1 (3175 50)(3175 100);
WIRE 17 -1 (3175 100)(3175 150);
WIRE 17 -1 (3175 150)(3175 200);
WIRE 17 -1 (3175 200)(3175 250);
WIRE 17 -1 (3175 250)(3175 300);
WIRE 17 -1 (3175 300)(4175 300);
FORCEPROP 2 LAST SIG_NAME P5E_CPU0_PE1_TX_DN<15:0>
J 0
(3315 310);
DISPLAY 0.680851 (3315 310);
PAINT WHITE (3315 310);
WIRE 17 -1 (-325 400)(-325 450);
WIRE 17 -1 (-325 450)(-325 500);
WIRE 17 -1 (-325 500)(-325 550);
WIRE 17 -1 (-325 550)(-325 600);
WIRE 17 -1 (-325 600)(-325 650);
WIRE 17 -1 (-325 650)(-325 700);
WIRE 17 -1 (-325 700)(-325 750);
WIRE 17 -1 (-325 750)(-325 800);
WIRE 17 -1 (-325 800)(-325 850);
WIRE 17 -1 (-325 850)(-325 900);
WIRE 17 -1 (-325 900)(-325 950);
WIRE 17 -1 (-325 950)(-325 1000);
WIRE 17 -1 (-325 1000)(-325 1050);
WIRE 17 -1 (-325 1050)(-325 1100);
WIRE 17 -1 (-325 1100)(-325 1150);
WIRE 17 -1 (-1475 1150)(-325 1150);
FORCEPROP 2 LAST SIG_NAME P5E_CPU0_PE1_RX_DP<15:0>
J 0
(-1360 1160);
DISPLAY 0.680851 (-1360 1160);
PAINT WHITE (-1360 1160);
WIRE 17 -1 (-325 -450)(-325 -400);
WIRE 17 -1 (-325 -400)(-325 -350);
WIRE 17 -1 (-325 -350)(-325 -300);
WIRE 17 -1 (-325 -300)(-325 -250);
WIRE 17 -1 (-325 -250)(-325 -200);
WIRE 17 -1 (-325 -200)(-325 -150);
WIRE 17 -1 (-325 -150)(-325 -100);
WIRE 17 -1 (-325 -100)(-325 -50);
WIRE 17 -1 (-325 -50)(-325 0);
WIRE 17 -1 (-325 0)(-325 50);
WIRE 17 -1 (-325 50)(-325 100);
WIRE 17 -1 (-325 100)(-325 150);
WIRE 17 -1 (-325 150)(-325 200);
WIRE 17 -1 (-325 200)(-325 250);
WIRE 17 -1 (-325 250)(-325 300);
WIRE 17 -1 (-1475 300)(-325 300);
FORCEPROP 2 LAST SIG_NAME P5E_CPU0_PE1_RX_DN<15:0>
J 0
(-1360 310);
DISPLAY 0.680851 (-1360 310);
PAINT WHITE (-1360 310);
WIRE 16 -1 (-225 275)(200 275);
WIRE 16 -1 (-225 225)(200 225);
WIRE 16 -1 (-225 175)(200 175);
WIRE 16 -1 (-225 125)(200 125);
WIRE 16 -1 (-225 75)(200 75);
WIRE 16 -1 (-225 25)(200 25);
WIRE 16 -1 (-225 -25)(200 -25);
WIRE 16 -1 (-225 -75)(200 -75);
WIRE 16 -1 (-225 -125)(200 -125);
WIRE 16 -1 (-225 -175)(200 -175);
WIRE 16 -1 (-225 -225)(200 -225);
WIRE 16 -1 (-225 -275)(200 -275);
WIRE 16 -1 (-225 -325)(200 -325);
WIRE 16 -1 (-225 -375)(200 -375);
WIRE 16 -1 (-225 -425)(200 -425);
WIRE 16 -1 (-225 -475)(200 -475);
WIRE 16 -1 (-225 1125)(200 1125);
WIRE 16 -1 (-225 1075)(200 1075);
WIRE 16 -1 (-225 1025)(200 1025);
WIRE 16 -1 (-225 975)(200 975);
WIRE 16 -1 (-225 925)(200 925);
WIRE 16 -1 (-225 875)(200 875);
WIRE 16 -1 (-225 825)(200 825);
WIRE 16 -1 (-225 775)(200 775);
WIRE 16 -1 (-225 725)(200 725);
WIRE 16 -1 (-225 675)(200 675);
WIRE 16 -1 (-225 625)(200 625);
WIRE 16 -1 (-225 575)(200 575);
WIRE 16 -1 (-225 525)(200 525);
WIRE 16 -1 (-225 475)(200 475);
WIRE 16 -1 (-225 425)(200 425);
WIRE 16 -1 (-225 375)(200 375);
WIRE 16 -1 (2600 275)(3075 275);
WIRE 16 -1 (2600 225)(3075 225);
WIRE 16 -1 (2600 175)(3075 175);
WIRE 16 -1 (2600 125)(3075 125);
WIRE 16 -1 (2600 75)(3075 75);
WIRE 16 -1 (2600 25)(3075 25);
WIRE 16 -1 (2600 -25)(3075 -25);
WIRE 16 -1 (2600 -75)(3075 -75);
WIRE 16 -1 (2600 -125)(3075 -125);
WIRE 16 -1 (2600 -175)(3075 -175);
WIRE 16 -1 (2600 -225)(3075 -225);
WIRE 16 -1 (2600 -275)(3075 -275);
WIRE 16 -1 (2600 -325)(3075 -325);
WIRE 16 -1 (2600 -375)(3075 -375);
WIRE 16 -1 (2600 -425)(3075 -425);
WIRE 16 -1 (2600 -475)(3075 -475);
WIRE 16 -1 (2600 1125)(3075 1125);
WIRE 16 -1 (2600 1075)(3075 1075);
WIRE 16 -1 (2600 1025)(3075 1025);
WIRE 16 -1 (2600 975)(3075 975);
WIRE 16 -1 (2600 925)(3075 925);
WIRE 16 -1 (2600 875)(3075 875);
WIRE 16 -1 (2600 825)(3075 825);
WIRE 16 -1 (2600 775)(3075 775);
WIRE 16 -1 (2600 725)(3075 725);
WIRE 16 -1 (2600 675)(3075 675);
WIRE 16 -1 (2600 625)(3075 625);
WIRE 16 -1 (2600 575)(3075 575);
WIRE 16 -1 (2600 525)(3075 525);
WIRE 16 -1 (2600 475)(3075 475);
WIRE 16 -1 (2600 425)(3075 425);
WIRE 16 -1 (2600 375)(3075 375);
WIRE 16 -1 (-225 3025)(200 3025);
WIRE 16 -1 (-225 2975)(200 2975);
WIRE 16 -1 (-225 2925)(200 2925);
WIRE 16 -1 (-225 2875)(200 2875);
WIRE 16 -1 (-225 2825)(200 2825);
WIRE 16 -1 (-225 2775)(200 2775);
WIRE 16 -1 (-225 2725)(200 2725);
WIRE 16 -1 (-225 2675)(200 2675);
WIRE 16 -1 (-225 2625)(200 2625);
WIRE 16 -1 (-225 2575)(200 2575);
WIRE 16 -1 (-225 2525)(200 2525);
WIRE 16 -1 (-225 2475)(200 2475);
WIRE 16 -1 (-225 2425)(200 2425);
WIRE 16 -1 (-225 2375)(200 2375);
WIRE 16 -1 (-225 2325)(200 2325);
WIRE 16 -1 (-225 2275)(200 2275);
WIRE 16 -1 (-225 3875)(200 3875);
WIRE 16 -1 (-225 3825)(200 3825);
WIRE 16 -1 (-225 3775)(200 3775);
WIRE 16 -1 (-225 3725)(200 3725);
WIRE 16 -1 (-225 3675)(200 3675);
WIRE 16 -1 (-225 3625)(200 3625);
WIRE 16 -1 (-225 3575)(200 3575);
WIRE 16 -1 (-225 3525)(200 3525);
WIRE 16 -1 (-225 3475)(200 3475);
WIRE 16 -1 (-225 3425)(200 3425);
WIRE 16 -1 (-225 3375)(200 3375);
WIRE 16 -1 (-225 3325)(200 3325);
WIRE 16 -1 (-225 3275)(200 3275);
WIRE 16 -1 (-225 3225)(200 3225);
WIRE 16 -1 (-225 3175)(200 3175);
WIRE 16 -1 (-225 3125)(200 3125);
WIRE 16 -1 (2600 3025)(3075 3025);
WIRE 16 -1 (2600 2975)(3075 2975);
WIRE 16 -1 (2600 2925)(3075 2925);
WIRE 16 -1 (2600 2875)(3075 2875);
WIRE 16 -1 (2600 2825)(3075 2825);
WIRE 16 -1 (2600 2775)(3075 2775);
WIRE 16 -1 (2600 2725)(3075 2725);
WIRE 16 -1 (2600 2675)(3075 2675);
WIRE 16 -1 (2600 2625)(3075 2625);
WIRE 16 -1 (2600 2575)(3075 2575);
WIRE 16 -1 (2600 2525)(3075 2525);
WIRE 16 -1 (2600 2475)(3075 2475);
WIRE 16 -1 (2600 2425)(3075 2425);
WIRE 16 -1 (2600 2375)(3075 2375);
WIRE 16 -1 (2600 2325)(3075 2325);
WIRE 16 -1 (2600 2275)(3075 2275);
WIRE 16 -1 (2600 3875)(3075 3875);
WIRE 16 -1 (2600 3825)(3075 3825);
WIRE 16 -1 (2600 3775)(3075 3775);
WIRE 16 -1 (2600 3725)(3075 3725);
WIRE 16 -1 (2600 3675)(3075 3675);
WIRE 16 -1 (2600 3625)(3075 3625);
WIRE 16 -1 (2600 3575)(3075 3575);
WIRE 16 -1 (2600 3525)(3075 3525);
WIRE 16 -1 (2600 3475)(3075 3475);
WIRE 16 -1 (2600 3425)(3075 3425);
WIRE 16 -1 (2600 3375)(3075 3375);
WIRE 16 -1 (2600 3325)(3075 3325);
WIRE 16 -1 (2600 3275)(3075 3275);
WIRE 16 -1 (2600 3225)(3075 3225);
WIRE 16 -1 (2600 3175)(3075 3175);
WIRE 16 -1 (2600 3125)(3075 3125);
FORCENOTE
20210818 MODIFY FOR GT
(200 4750) 0;
DISPLAY LEFT (200 4750);
DISPLAY 2.510638 (200 4750);
PAINT PINK (200 4750);
QUIT
